G04 ================== begin FILE IDENTIFICATION RECORD ==================*
G04 Layout Name:  12433-2a.brd*
G04 Film Name:    L2GND*
G04 File Format:  Gerber RS274X*
G04 File Origin:  Cadence Allegro 16.5-S056*
G04 Origin Date:  Fri Dec 11 16:47:40 2015*
G04 *
G04 Layer:  VIA CLASS/L2GND*
G04 Layer:  PIN/L2GND*
G04 Layer:  ETCH/L2GND*
G04 Layer:  DRAWING FORMAT/LAYER_PCB_STORY*
G04 Layer:  DRAWING FORMAT/LAYER_L2GND*
G04 *
G04 Offset:    (0.00 0.00)*
G04 Mirror:    No*
G04 Mode:      Negative*
G04 Rotation:  0*
G04 FullContactRelief:  No*
G04 UndefLineWidth:     6.00*
G04 ================== end FILE IDENTIFICATION RECORD ====================*
%FSLAX35Y35*MOIN*%
%IR0*IPPOS*OFA0.00000B0.00000*MIA0B0*SFA1.00000B1.00000*%
%AMMACRO28*
4,1,17,-.09386,.06558,
-.103822,.048285,
-.110629,.029523,
-.114075,.009864,
-.114055,-.010095,
-.110569,-.029747,
-.103724,-.048495,
-.09386,-.06558,
-.09745,-.06917,
-.107981,-.051197,
-.115231,-.031669,
-.118979,-.011178,
-.119113,.009652,
-.115627,.030189,
-.108628,.049809,
-.098328,.067916,
-.09745,.06917,
-.09386,.06558,
90.*
4,1,17,-.06558,-.09386,
-.048285,-.103822,
-.029523,-.110629,
-.009864,-.114075,
.010095,-.114055,
.029747,-.110569,
.048495,-.103724,
.06558,-.09386,
.06917,-.09745,
.051197,-.107981,
.031669,-.115231,
.011178,-.118979,
-.009652,-.119113,
-.030189,-.115627,
-.049809,-.108628,
-.067916,-.098328,
-.06917,-.09745,
-.06558,-.09386,
90.*
4,1,17,.09386,-.06558,
.103822,-.048285,
.110629,-.029523,
.114075,-.009864,
.114055,.010095,
.110569,.029747,
.103724,.048495,
.09386,.06558,
.09745,.06917,
.107981,.051197,
.115231,.031669,
.118979,.011178,
.119113,-.009652,
.115627,-.030189,
.108628,-.049809,
.098328,-.067916,
.09745,-.06917,
.09386,-.06558,
90.*
4,1,17,.06558,.09386,
.048285,.103822,
.029523,.110629,
.009864,.114075,
-.010095,.114055,
-.029747,.110569,
-.048495,.103724,
-.06558,.09386,
-.06917,.09745,
-.051197,.107981,
-.031669,.115231,
-.011178,.118979,
.009652,.119113,
.030189,.115627,
.049809,.108628,
.067916,.098328,
.06917,.09745,
.06558,.09386,
90.*
%
%ADD28MACRO28*%
%AMMACRO19*
4,1,16,.07183,.04355,
.078301,.030415,
.082393,.016356,
.083982,.0018,
.083018,-.01281,
.079533,-.027032,
.07363,-.040432,
.07183,-.04355,
.07547,-.04718,
.082516,-.033358,
.087055,-.018522,
.088949,-.003124,
.08814,.012369,
.084653,.027487,
.078594,.041769,
.07547,.04718,
.07183,.04355,
0.0*
4,1,16,.04355,-.07183,
.030415,-.078301,
.016356,-.082393,
.0018,-.083982,
-.01281,-.083018,
-.027032,-.079533,
-.040432,-.07363,
-.04355,-.07183,
-.04718,-.07547,
-.033358,-.082516,
-.018522,-.087055,
-.003124,-.088949,
.012369,-.08814,
.027487,-.084653,
.041769,-.078594,
.04718,-.07547,
.04355,-.07183,
0.0*
4,1,16,-.07183,-.04355,
-.078301,-.030415,
-.082393,-.016356,
-.083982,-.0018,
-.083018,.01281,
-.079533,.027032,
-.07363,.040432,
-.07183,.04355,
-.07547,.04718,
-.082516,.033358,
-.087055,.018522,
-.088949,.003124,
-.08814,-.012369,
-.084653,-.027487,
-.078594,-.041769,
-.07547,-.04718,
-.07183,-.04355,
0.0*
4,1,16,-.04355,.07183,
-.030415,.078301,
-.016356,.082393,
-.0018,.083982,
.01281,.083018,
.027032,.079533,
.040432,.07363,
.04355,.07183,
.04718,.07547,
.033358,.082516,
.018522,.087055,
.003124,.088949,
-.012369,.08814,
-.027487,.084653,
-.041769,.078594,
-.04718,.07547,
-.04355,.07183,
0.0*
%
%ADD19MACRO19*%
%AMMACRO14*
4,1,16,.07909,.0508,
.08671,.036294,
.091695,.020686,
.093894,.004449,
.09324,-.011923,
.089753,-.027933,
.083539,-.043094,
.07909,-.0508,
.0827,-.05442,
.090894,-.039233,
.096325,-.022853,
.09883,-.005779,
.098332,.01147,
.094847,.028371,
.088479,.04441,
.0827,.05442,
.07909,.0508,
0.0*
4,1,16,.0508,-.07909,
.036294,-.08671,
.020686,-.091695,
.004449,-.093894,
-.011923,-.09324,
-.027933,-.089753,
-.043094,-.083539,
-.0508,-.07909,
-.05442,-.0827,
-.039233,-.090894,
-.022853,-.096325,
-.005779,-.09883,
.01147,-.098332,
.028371,-.094847,
.04441,-.088479,
.05442,-.0827,
.0508,-.07909,
0.0*
4,1,16,-.07909,-.0508,
-.08671,-.036294,
-.091695,-.020686,
-.093894,-.004449,
-.09324,.011923,
-.089753,.027933,
-.083539,.043094,
-.07909,.0508,
-.0827,.05442,
-.090894,.039233,
-.096325,.022853,
-.09883,.005779,
-.098332,-.01147,
-.094847,-.028371,
-.088479,-.04441,
-.0827,-.05442,
-.07909,-.0508,
0.0*
4,1,16,-.0508,.07909,
-.036294,.08671,
-.020686,.091695,
-.004449,.093894,
.011923,.09324,
.027933,.089753,
.043094,.083539,
.0508,.07909,
.05442,.0827,
.039233,.090894,
.022853,.096325,
.005779,.09883,
-.01147,.098332,
-.028371,.094847,
-.04441,.088479,
-.05442,.0827,
-.0508,.07909,
0.0*
%
%ADD14MACRO14*%
%ADD15C,.032*%
%ADD17C,.036*%
%ADD16C,.063*%
%ADD13C,.068*%
%ADD25C,.069*%
%AMMACRO20*
4,1,15,.00398,.00044,
.003999,.000208,
.004004,-.000025,
.003996,-.000258,
.00398,-.00044,
.00483,-.00129,
.004897,-.001007,
.004947,-.000721,
.004981,-.000432,
.004997,-.000141,
.004997,.000149,
.00498,.00044,
.004946,.000729,
.004895,.001015,
.00483,.00129,
.00398,.00044,
90.*
4,1,15,.00044,-.00398,
.000208,-.003999,
-.000025,-.004004,
-.000258,-.003996,
-.00044,-.00398,
-.00129,-.00483,
-.001007,-.004897,
-.000721,-.004947,
-.000432,-.004981,
-.000141,-.004997,
.000149,-.004997,
.00044,-.00498,
.000729,-.004946,
.001015,-.004895,
.00129,-.00483,
.00044,-.00398,
90.*
4,1,15,-.00398,-.00044,
-.003999,-.000208,
-.004004,.000025,
-.003996,.000258,
-.00398,.00044,
-.00483,.00129,
-.004897,.001007,
-.004947,.000721,
-.004981,.000432,
-.004997,.000141,
-.004997,-.000149,
-.00498,-.00044,
-.004946,-.000729,
-.004895,-.001015,
-.00483,-.00129,
-.00398,-.00044,
90.*
4,1,15,-.00044,.00398,
-.000208,.003999,
.000025,.004004,
.000258,.003996,
.00044,.00398,
.00129,.00483,
.001007,.004897,
.000721,.004947,
.000432,.004981,
.000141,.004997,
-.000149,.004997,
-.00044,.00498,
-.000729,.004946,
-.001015,.004895,
-.00129,.00483,
-.00044,.00398,
90.*
%
%ADD20MACRO20*%
%AMMACRO12*
4,1,15,.00398,.00044,
.003999,.000208,
.004004,-.000025,
.003996,-.000258,
.00398,-.00044,
.00483,-.00129,
.004897,-.001007,
.004947,-.000721,
.004981,-.000432,
.004997,-.000141,
.004997,.000149,
.00498,.00044,
.004946,.000729,
.004895,.001015,
.00483,.00129,
.00398,.00044,
0.0*
4,1,15,.00044,-.00398,
.000208,-.003999,
-.000025,-.004004,
-.000258,-.003996,
-.00044,-.00398,
-.00129,-.00483,
-.001007,-.004897,
-.000721,-.004947,
-.000432,-.004981,
-.000141,-.004997,
.000149,-.004997,
.00044,-.00498,
.000729,-.004946,
.001015,-.004895,
.00129,-.00483,
.00044,-.00398,
0.0*
4,1,15,-.00398,-.00044,
-.003999,-.000208,
-.004004,.000025,
-.003996,.000258,
-.00398,.00044,
-.00483,.00129,
-.004897,.001007,
-.004947,.000721,
-.004981,.000432,
-.004997,.000141,
-.004997,-.000149,
-.00498,-.00044,
-.004946,-.000729,
-.004895,-.001015,
-.00483,-.00129,
-.00398,-.00044,
0.0*
4,1,15,-.00044,.00398,
-.000208,.003999,
.000025,.004004,
.000258,.003996,
.00044,.00398,
.00129,.00483,
.001007,.004897,
.000721,.004947,
.000432,.004981,
.000141,.004997,
-.000149,.004997,
-.00044,.00498,
-.000729,.004946,
-.001015,.004895,
-.00129,.00483,
-.00044,.00398,
0.0*
%
%ADD12MACRO12*%
%AMMACRO18*
4,1,13,.02632,.01218,
.028035,.007425,
.028899,.002443,
.028884,-.002612,
.027991,-.007588,
.02632,-.01218,
.03005,-.01591,
.032356,-.01045,
.033679,-.004673,
.033979,.001247,
.033246,.007128,
.031504,.012793,
.03005,.01591,
.02632,.01218,
270.*
4,1,13,.01218,-.02632,
.007425,-.028035,
.002443,-.028899,
-.002612,-.028884,
-.007588,-.027991,
-.01218,-.02632,
-.01591,-.03005,
-.01045,-.032356,
-.004673,-.033679,
.001247,-.033979,
.007128,-.033246,
.012793,-.031504,
.01591,-.03005,
.01218,-.02632,
270.*
4,1,13,-.02632,-.01218,
-.028035,-.007425,
-.028899,-.002443,
-.028884,.002612,
-.027991,.007588,
-.02632,.01218,
-.03005,.01591,
-.032356,.01045,
-.033679,.004673,
-.033979,-.001247,
-.033246,-.007128,
-.031504,-.012793,
-.03005,-.01591,
-.02632,-.01218,
270.*
4,1,13,-.01218,.02632,
-.007425,.028035,
-.002443,.028899,
.002612,.028884,
.007588,.027991,
.01218,.02632,
.01591,.03005,
.01045,.032356,
.004673,.033679,
-.001247,.033979,
-.007128,.033246,
-.012793,.031504,
-.01591,.03005,
-.01218,.02632,
270.*
%
%ADD18MACRO18*%
%AMMACRO24*
4,1,14,.0267,.01255,
.028474,.007723,
.029382,.002661,
.029398,-.002481,
.02852,-.007549,
.026776,-.012386,
.0267,-.01255,
.03042,-.01628,
.032785,-.01075,
.034154,-.004894,
.034484,.001111,
.033768,.007082,
.032025,.012838,
.03042,.01628,
.0267,.01255,
270.*
4,1,14,.01255,-.0267,
.007723,-.028474,
.002661,-.029382,
-.002481,-.029398,
-.007549,-.02852,
-.012386,-.026776,
-.01255,-.0267,
-.01628,-.03042,
-.01075,-.032785,
-.004894,-.034154,
.001111,-.034484,
.007082,-.033768,
.012838,-.032025,
.01628,-.03042,
.01255,-.0267,
270.*
4,1,14,-.0267,-.01255,
-.028474,-.007723,
-.029382,-.002661,
-.029398,.002481,
-.02852,.007549,
-.026776,.012386,
-.0267,.01255,
-.03042,.01628,
-.032785,.01075,
-.034154,.004894,
-.034484,-.001111,
-.033768,-.007082,
-.032025,-.012838,
-.03042,-.01628,
-.0267,-.01255,
270.*
4,1,14,-.01255,.0267,
-.007723,.028474,
-.002661,.029382,
.002481,.029398,
.007549,.02852,
.012386,.026776,
.01255,.0267,
.01628,.03042,
.01075,.032785,
.004894,.034154,
-.001111,.034484,
-.007082,.033768,
-.012838,.032025,
-.01628,.03042,
-.01255,.0267,
270.*
%
%ADD24MACRO24*%
%ADD21C,.143*%
%ADD11C,.17*%
%ADD23C,.127*%
%ADD22C,.154*%
%AMMACRO29*
4,1,15,.00398,.00044,
.003999,.000208,
.004004,-.000025,
.003996,-.000258,
.00398,-.00044,
.00483,-.00129,
.004897,-.001007,
.004947,-.000721,
.004981,-.000432,
.004997,-.000141,
.004997,.000149,
.00498,.00044,
.004946,.000729,
.004895,.001015,
.00483,.00129,
.00398,.00044,
89.996*
4,1,15,.00044,-.00398,
.000208,-.003999,
-.000025,-.004004,
-.000258,-.003996,
-.00044,-.00398,
-.00129,-.00483,
-.001007,-.004897,
-.000721,-.004947,
-.000432,-.004981,
-.000141,-.004997,
.000149,-.004997,
.00044,-.00498,
.000729,-.004946,
.001015,-.004895,
.00129,-.00483,
.00044,-.00398,
89.996*
4,1,15,-.00398,-.00044,
-.003999,-.000208,
-.004004,.000025,
-.003996,.000258,
-.00398,.00044,
-.00483,.00129,
-.004897,.001007,
-.004947,.000721,
-.004981,.000432,
-.004997,.000141,
-.004997,-.000149,
-.00498,-.00044,
-.004946,-.000729,
-.004895,-.001015,
-.00483,-.00129,
-.00398,-.00044,
89.996*
4,1,15,-.00044,.00398,
-.000208,.003999,
.000025,.004004,
.000258,.003996,
.00044,.00398,
.00129,.00483,
.001007,.004897,
.000721,.004947,
.000432,.004981,
.000141,.004997,
-.000149,.004997,
-.00044,.00498,
-.000729,.004946,
-.001015,.004895,
-.00129,.00483,
-.00044,.00398,
89.996*
%
%ADD29MACRO29*%
%ADD10C,.168*%
%AMMACRO27*
4,1,15,.00398,.00044,
.003999,.000208,
.004004,-.000025,
.003996,-.000258,
.00398,-.00044,
.00483,-.00129,
.004897,-.001007,
.004947,-.000721,
.004981,-.000432,
.004997,-.000141,
.004997,.000149,
.00498,.00044,
.004946,.000729,
.004895,.001015,
.00483,.00129,
.00398,.00044,
270.*
4,1,15,.00044,-.00398,
.000208,-.003999,
-.000025,-.004004,
-.000258,-.003996,
-.00044,-.00398,
-.00129,-.00483,
-.001007,-.004897,
-.000721,-.004947,
-.000432,-.004981,
-.000141,-.004997,
.000149,-.004997,
.00044,-.00498,
.000729,-.004946,
.001015,-.004895,
.00129,-.00483,
.00044,-.00398,
270.*
4,1,15,-.00398,-.00044,
-.003999,-.000208,
-.004004,.000025,
-.003996,.000258,
-.00398,.00044,
-.00483,.00129,
-.004897,.001007,
-.004947,.000721,
-.004981,.000432,
-.004997,.000141,
-.004997,-.000149,
-.00498,-.00044,
-.004946,-.000729,
-.004895,-.001015,
-.00483,-.00129,
-.00398,-.00044,
270.*
4,1,15,-.00044,.00398,
-.000208,.003999,
.000025,.004004,
.000258,.003996,
.00044,.00398,
.00129,.00483,
.001007,.004897,
.000721,.004947,
.000432,.004981,
.000141,.004997,
-.000149,.004997,
-.00044,.00498,
-.000729,.004946,
-.001015,.004895,
-.00129,.00483,
-.00044,.00398,
270.*
%
%ADD27MACRO27*%
%AMMACRO26*
4,1,15,.00398,.00044,
.003999,.000208,
.004004,-.000025,
.003996,-.000258,
.00398,-.00044,
.00483,-.00129,
.004897,-.001007,
.004947,-.000721,
.004981,-.000432,
.004997,-.000141,
.004997,.000149,
.00498,.00044,
.004946,.000729,
.004895,.001015,
.00483,.00129,
.00398,.00044,
180.*
4,1,15,.00044,-.00398,
.000208,-.003999,
-.000025,-.004004,
-.000258,-.003996,
-.00044,-.00398,
-.00129,-.00483,
-.001007,-.004897,
-.000721,-.004947,
-.000432,-.004981,
-.000141,-.004997,
.000149,-.004997,
.00044,-.00498,
.000729,-.004946,
.001015,-.004895,
.00129,-.00483,
.00044,-.00398,
180.*
4,1,15,-.00398,-.00044,
-.003999,-.000208,
-.004004,.000025,
-.003996,.000258,
-.00398,.00044,
-.00483,.00129,
-.004897,.001007,
-.004947,.000721,
-.004981,.000432,
-.004997,.000141,
-.004997,-.000149,
-.00498,-.00044,
-.004946,-.000729,
-.004895,-.001015,
-.00483,-.00129,
-.00398,-.00044,
180.*
4,1,15,-.00044,.00398,
-.000208,.003999,
.000025,.004004,
.000258,.003996,
.00044,.00398,
.00129,.00483,
.001007,.004897,
.000721,.004947,
.000432,.004981,
.000141,.004997,
-.000149,.004997,
-.00044,.00498,
-.000729,.004946,
-.001015,.004895,
-.00129,.00483,
-.00044,.00398,
180.*
%
%ADD26MACRO26*%
%ADD30C,.02*%
%ADD31C,.006*%
%ADD33C,.08824*%
%ADD36C,.12304*%
%ADD35C,.15004*%
%ADD34C,.13904*%
%ADD32C,.16604*%
G75*
%LPD*%
G75*
G36*
G01X-6000Y-6000D02*
X212693D01*
Y1974504D01*
X-6000D01*
Y-6000D01*
G37*
%LPC*%
G75*
G36*
G01X65894Y3937D02*
G02X64961Y3004I-933J0D01*
G01X3937D01*
G02X3004Y3937I0J933D01*
G01Y1964567D01*
G02X3937Y1965500I933J0D01*
G01X64961D01*
G02X65894Y1964567I0J-933D01*
G01Y1933070D01*
G03X65898Y1932838I6941J4D01*
G01Y1931828D01*
X66032Y1931695D01*
X66044Y1931637D01*
G03X71401Y1926280I6791J1434D01*
G01X71459Y1926268D01*
X71592Y1926134D01*
X72602D01*
G03X72834Y1926130I236J6937D01*
G01X82250D01*
Y1874811D01*
X80689Y1873250D01*
X62189D01*
X59250Y1870311D01*
Y1752311D01*
X49750Y1742811D01*
Y1675689D01*
X54189Y1671250D01*
X126811D01*
X130250Y1674689D01*
Y1774311D01*
X129311Y1775250D01*
X126811D01*
X125250Y1776811D01*
Y1779689D01*
X130250Y1784689D01*
Y1863311D01*
X120311Y1873250D01*
X90311D01*
X89250Y1874311D01*
Y1926130D01*
X202756D01*
G02X203689Y1925197I0J-933D01*
G01Y43307D01*
G02X202756Y42374I-933J0D01*
G01X72834D01*
G03X72602Y42370I4J-6941D01*
G01X71592D01*
X71459Y42236D01*
X71401Y42224D01*
G03X66044Y36867I1434J-6791D01*
G01X66032Y36809D01*
X65898Y36676D01*
Y35666D01*
G03X65894Y35434I6937J-236D01*
G01Y3937D01*
G37*
G36*
G01X126189Y1773750D02*
X128689D01*
X128750Y1773689D01*
Y1675311D01*
X126189Y1672750D01*
X54811D01*
X51250Y1676311D01*
Y1742189D01*
X60750Y1751689D01*
Y1869689D01*
X62811Y1871750D01*
X81311D01*
X83750Y1874189D01*
Y1926130D01*
X87750D01*
Y1873689D01*
X89689Y1871750D01*
X119689D01*
X128750Y1862689D01*
Y1785311D01*
X123750Y1780311D01*
Y1776189D01*
X126189Y1773750D01*
G37*
%LPD*%
G75*
G54D33*
X15906Y88110D03*
Y781181D03*
Y1227323D03*
Y1487165D03*
Y1920394D03*
G54D36*
X80709Y139409D03*
Y309409D03*
X149606Y139409D03*
Y309409D03*
G54D35*
X80709Y119409D03*
Y329409D03*
X149606Y119409D03*
Y329409D03*
G54D34*
X47244Y68110D03*
Y501338D03*
Y761181D03*
Y1207323D03*
Y1467165D03*
Y1900393D03*
G54D32*
X29921Y24803D03*
Y111417D03*
Y458031D03*
Y544646D03*
Y717874D03*
Y804488D03*
X30000Y1164000D03*
X29921Y1250630D03*
Y1423858D03*
Y1510472D03*
Y1857086D03*
Y1943701D03*
G54D28*
X96457Y1747835D03*
Y1823031D03*
X178937Y1328740D03*
X161417Y1747835D03*
Y1823031D03*
G54D19*
X27559Y629921D03*
X17716Y1338583D03*
X27559Y1811023D03*
X179134Y78740D03*
X179133Y570866D03*
X179134Y1161417D03*
G54D14*
X27559Y157480D03*
X179134Y1889764D03*
G54D15*
X32425Y177900D03*
X26450Y274750D03*
X25500Y321200D03*
X21600Y333800D03*
X33450Y574300D03*
X23450Y577491D03*
X25148Y570800D03*
X27000Y573800D03*
X13300Y1644300D03*
X10500Y1648800D03*
X13300Y1689600D03*
X19200Y1707000D03*
X25000Y1763800D03*
X64000Y67553D03*
X64500Y53000D03*
X70454Y60031D03*
X81500Y75500D03*
X63500Y63500D03*
X75300Y155300D03*
X49924Y153261D03*
X53400Y191300D03*
X39300Y175500D03*
X43700Y181200D03*
X43400Y174325D03*
X52700Y162300D03*
X64400Y183400D03*
X52500Y175200D03*
X70500Y190200D03*
X54400Y217000D03*
X65200Y207850D03*
X57424Y232974D03*
X42720Y233990D03*
X65000Y241500D03*
Y235400D03*
X41100Y231000D03*
X71400Y208150D03*
X69900Y236600D03*
X77900Y229034D03*
X70600Y217600D03*
X74800Y231800D03*
X69400Y226100D03*
X61300Y229400D03*
X38000Y228500D03*
X75300Y211300D03*
X85676Y231100D03*
X72100Y221700D03*
X49700Y209700D03*
X53500Y199700D03*
X47800Y199200D03*
X64000Y199700D03*
X60300Y275700D03*
X57500Y268500D03*
X68000Y268000D03*
X70600Y250500D03*
X42500Y254100D03*
X48500Y248600D03*
X54000Y275600D03*
X45800Y277800D03*
X43400Y272300D03*
X78000Y429500D03*
X52100Y513100D03*
X46500Y511000D03*
X46000Y516000D03*
X77800Y540300D03*
X63400Y581400D03*
X75571Y692496D03*
X53000Y673500D03*
X57684Y697639D03*
X86597Y681103D03*
X43388Y694286D03*
X49500Y703500D03*
X46500Y705500D03*
X44500Y697500D03*
X60900Y670200D03*
X60500Y682540D03*
X76100Y686900D03*
X83850Y678109D03*
X73000Y728000D03*
X69000Y726800D03*
X86500Y723500D03*
X57500Y844500D03*
X72400Y822900D03*
X51200Y827000D03*
X61207Y828350D03*
X49600Y889400D03*
X55700Y880000D03*
X56000Y885500D03*
X64600Y882700D03*
X61600Y885200D03*
X67200Y888800D03*
X54000Y996500D03*
X53500Y1025500D03*
X51000Y1018000D03*
X82094Y1112500D03*
X37500Y1099823D03*
X70500Y1161500D03*
X73163Y1158780D03*
X71100Y1171000D03*
X68800Y1178800D03*
X67700Y1568700D03*
X83000Y1619703D03*
X83050Y1616000D03*
X45300Y1776300D03*
X109500Y62000D03*
X89500Y49500D03*
X99500Y61000D03*
X115000Y76500D03*
X109000D03*
X98500Y73000D03*
X115500Y59500D03*
X97000Y51500D03*
X91500Y88500D03*
Y92500D03*
X88253Y65500D03*
X112000Y101000D03*
X104500D03*
X91000Y97000D03*
X93000Y107000D03*
X93900Y111800D03*
X93500Y101500D03*
X117600Y234900D03*
X122100Y230100D03*
X127200Y246000D03*
X122500Y441000D03*
X135500D03*
X91300Y528200D03*
X110400Y550800D03*
X87700Y528000D03*
X132500Y539621D03*
X115300Y551800D03*
X129000Y597000D03*
X116000Y596900D03*
X113655Y599363D03*
X128900Y580500D03*
X122300Y575000D03*
X131135Y639554D03*
X122500Y653650D03*
X117400Y653100D03*
X91250Y704700D03*
X100200Y663900D03*
X118127Y663400D03*
X109005Y665890D03*
X114000Y663350D03*
X98900Y822900D03*
X114900Y824100D03*
X106404Y840700D03*
X100300Y841000D03*
X111500Y851600D03*
X101500Y874200D03*
X102300Y863438D03*
X107164Y862285D03*
X113400Y862200D03*
X127200Y1015200D03*
X119500Y1261000D03*
X119000Y1255968D03*
X128700Y1408000D03*
X135601Y1416200D03*
X134500Y1420000D03*
X131174Y1412700D03*
X89000Y1428171D03*
X110000Y1429500D03*
X132000Y1436500D03*
X112750Y1491250D03*
X121000Y1506500D03*
X113000D03*
X117000D03*
X109000D03*
X133000Y1505500D03*
X128999Y1506499D03*
X125000Y1506500D03*
X135008Y1508245D03*
X132300Y1491100D03*
X108500Y1569000D03*
X113200Y1622800D03*
Y1619300D03*
X146960Y432400D03*
X165300Y481100D03*
X144000Y509500D03*
X166100Y527900D03*
X162500D03*
X159850Y541800D03*
X182588Y542288D03*
X154600Y581500D03*
X159250Y590250D03*
X160000Y562500D03*
X147900Y588100D03*
X138900Y650100D03*
X139200Y653900D03*
X174196Y628196D03*
X150978Y687775D03*
X142648Y665429D03*
X155200Y679500D03*
X161500Y691700D03*
X150700D03*
X153192Y705890D03*
X158600Y752600D03*
X157800Y898000D03*
X147500Y900500D03*
X143000Y953032D03*
X146500Y953030D03*
X149772Y954121D03*
X152747Y952474D03*
X150500Y976500D03*
X155000Y974500D03*
X139900Y1415100D03*
X142500Y1420500D03*
X158500Y1466500D03*
X151500Y1438500D03*
X157500Y1454800D03*
X142000Y1494800D03*
X147500Y1498000D03*
X153500Y1496500D03*
X143518Y1567520D03*
X177500Y1569500D03*
X141300Y1625000D03*
X169876Y1626303D03*
X141500Y1621600D03*
X173270Y1626517D03*
X191400Y432405D03*
G54D16*
X31299Y230866D03*
Y220866D03*
Y210866D03*
Y348563D03*
Y338563D03*
Y358563D03*
Y903917D03*
Y923917D03*
Y913917D03*
Y1064587D03*
Y1054587D03*
Y1044587D03*
Y1619941D03*
Y1609941D03*
Y1629941D03*
Y1757638D03*
Y1747638D03*
Y1737638D03*
G54D17*
X28050Y256950D03*
X31600Y1024300D03*
X19250Y1663100D03*
X13900Y1706200D03*
X86000Y296000D03*
X68000D03*
X76000D03*
X68000Y286000D03*
Y320000D03*
Y312000D03*
Y304000D03*
X74000Y390000D03*
X66000D03*
X58000D03*
X74000Y400000D03*
X66000D03*
X58000D03*
X64000Y446500D03*
Y451000D03*
X74000Y408000D03*
X66000D03*
Y418000D03*
X74000D03*
X73700Y423000D03*
X66000Y426000D03*
X58000D03*
Y408000D03*
Y417500D03*
X84500Y433000D03*
X58100Y431900D03*
X63096Y434540D03*
X68500Y434300D03*
X81000Y410500D03*
X86400D03*
X78200Y501000D03*
X82000Y483600D03*
X46000Y490500D03*
X71900Y501000D03*
X50100Y493000D03*
X42500D03*
X78200Y481700D03*
X63300Y464400D03*
X64000Y455500D03*
Y460000D03*
X62500Y472900D03*
X62600Y468500D03*
X62500Y477000D03*
X78500Y506700D03*
X71800Y506900D03*
X85000Y506400D03*
X84500Y514400D03*
X72100Y521800D03*
X79400D03*
X72000Y514800D03*
X78000D03*
X51700Y522500D03*
X72500Y595900D03*
X56800Y576950D03*
X80900Y668400D03*
X86443Y662853D03*
X84504Y666353D03*
X56710Y681069D03*
X39096Y674917D03*
X43281Y674991D03*
X40000Y659000D03*
X41000Y931899D03*
X64000Y980500D03*
X37700Y991600D03*
X87000Y1064000D03*
X39300Y1105800D03*
X83500Y1072000D03*
Y1067000D03*
Y1076500D03*
X67302Y1133490D03*
X78292Y1148041D03*
X64500Y1165700D03*
X86900Y1451000D03*
X83500Y1469500D03*
X85200Y1515000D03*
X58500Y1519000D03*
X72000Y1514000D03*
X53500Y1519000D03*
X85000Y1490000D03*
X54500Y1574000D03*
X73900Y1535900D03*
X80000Y1531600D03*
X54300Y1541200D03*
X59500Y1541000D03*
X57500Y1562000D03*
X57000Y1568500D03*
X71600Y1607700D03*
X50600Y1589300D03*
Y1582800D03*
Y1595300D03*
Y1601300D03*
X55300Y1601100D03*
Y1595100D03*
Y1582600D03*
Y1589100D03*
X68700Y1603900D03*
X55400Y1613300D03*
X58500Y1607700D03*
X59500Y1667000D03*
X70000Y1668000D03*
X86000Y1669000D03*
X76000Y1646000D03*
X86000D03*
X76000Y1634000D03*
X86000D03*
Y1659500D03*
X75500D03*
X54000Y1646500D03*
X64500Y1646000D03*
X57500Y1634500D03*
X64000Y1634000D03*
X64500Y1658500D03*
X53500Y1659000D03*
X48400Y1746900D03*
X41600D03*
X38800Y1775000D03*
X42000Y1784400D03*
X39179Y1792306D03*
X114000Y296000D03*
X106000D03*
X96000D03*
X102000Y312000D03*
X104000Y304000D03*
X94000D03*
Y312000D03*
Y320000D03*
X134000Y396000D03*
X118000D03*
Y386000D03*
X134000D03*
X122500Y450500D03*
X117000Y449000D03*
X89800Y446000D03*
X136000Y447000D03*
X131000D03*
X91900Y410500D03*
X88500Y426500D03*
X134000Y404500D03*
X118000Y424000D03*
Y404000D03*
X130000Y432000D03*
X134000Y414000D03*
X118000D03*
X134000Y424000D03*
X129000Y485500D03*
X120000D03*
Y501500D03*
X110800Y482600D03*
X99800Y482000D03*
X110800Y488600D03*
X100000Y488000D03*
X110800Y500600D03*
X100000Y500000D03*
X129000Y501500D03*
X100000Y494000D03*
X110800Y494600D03*
X129000Y493500D03*
X120000D03*
X137000Y501500D03*
Y493000D03*
X136500Y485500D03*
X122500Y457500D03*
Y463500D03*
X121500Y475500D03*
X122500Y469500D03*
X117000Y455000D03*
Y460500D03*
Y466000D03*
Y471500D03*
X89800Y452900D03*
Y459000D03*
X111500Y473000D03*
X99500D03*
X89800Y464800D03*
X135500Y454000D03*
Y461000D03*
Y474500D03*
Y468000D03*
X130500Y454000D03*
Y461000D03*
Y468000D03*
Y474500D03*
X129000Y517500D03*
X100000Y512000D03*
X129000Y509500D03*
X110800Y512600D03*
X120000Y517500D03*
X100000Y506000D03*
X110800Y506600D03*
X120000Y509500D03*
Y523500D03*
X129000D03*
X137000Y510000D03*
X137500Y523500D03*
X100000Y519100D03*
X137500Y517500D03*
X90630Y602020D03*
X112800Y653500D03*
X108200Y655825D03*
X88967Y659749D03*
X90674Y663367D03*
X121500Y683500D03*
X119576Y687008D03*
X120702Y690847D03*
X100600Y670600D03*
X107000Y802400D03*
Y798200D03*
X106882Y794201D03*
X91400Y1064100D03*
X95500Y1064000D03*
X97250Y1023500D03*
X89000Y1167400D03*
X101500Y1127500D03*
X106000D03*
X97000D03*
X97500Y1132500D03*
X105500Y1415000D03*
X99600Y1416500D03*
X87200Y1440000D03*
X99800Y1455600D03*
X109500Y1438000D03*
X98500Y1428400D03*
X117000Y1435200D03*
X133799Y1440699D03*
X93000Y1518700D03*
X94000Y1514000D03*
X87900Y1523400D03*
X124500Y1524000D03*
X91300Y1488600D03*
X129000Y1555500D03*
X111500Y1537500D03*
X122000Y1558000D03*
X114000Y1552000D03*
X122000D03*
X114000Y1558000D03*
X122000Y1564000D03*
X121800Y1569929D03*
X114000Y1564000D03*
X122000Y1576000D03*
X102000Y1544000D03*
Y1562000D03*
Y1550000D03*
Y1556000D03*
Y1568000D03*
X94000D03*
X116000Y1576000D03*
X115900Y1569700D03*
X129000Y1535000D03*
X136000Y1568000D03*
X94000Y1556000D03*
X129000Y1549000D03*
X122000Y1538000D03*
X136000Y1542000D03*
X122000Y1546000D03*
X129000Y1542500D03*
X136000Y1536000D03*
X114000Y1546000D03*
X128000Y1568000D03*
X136000Y1562000D03*
Y1555000D03*
X129000Y1562500D03*
X136000Y1548000D03*
X119000Y1529500D03*
X94000Y1550000D03*
Y1562000D03*
X136000Y1528000D03*
X122000Y1584000D03*
X116000D03*
Y1592000D03*
X122000D03*
X116000Y1600000D03*
X122000Y1612000D03*
X104000Y1605500D03*
X116000Y1612000D03*
X122000Y1600000D03*
X128000Y1606000D03*
X94500Y1605500D03*
X113500D03*
X117500Y1669000D03*
X127500D03*
X97000D03*
X107000D03*
X127000Y1646000D03*
X138000Y1634000D03*
X137500Y1659500D03*
X118000Y1646000D03*
X138000D03*
X117000Y1633500D03*
X127500Y1633000D03*
Y1659500D03*
X117500D03*
X108000Y1646000D03*
X106000Y1634000D03*
X107000Y1659500D03*
X96000Y1646000D03*
X96500Y1634000D03*
X97000Y1659500D03*
X116948Y1892000D03*
X124500Y1892403D03*
X132000Y1892000D03*
X182000Y296000D03*
X172000D03*
X162000D03*
X142000Y291000D03*
X143400Y318700D03*
X174000Y316000D03*
X164000D03*
X172000Y310000D03*
X182000D03*
X184000Y303000D03*
X176000Y302000D03*
X166000D03*
X143300Y343400D03*
X151300Y298200D03*
X150000Y386000D03*
Y396000D03*
X161600Y445900D03*
X161900Y451600D03*
X174500Y432000D03*
X162000D03*
X145500Y427000D03*
X142000Y432000D03*
X150000Y404000D03*
Y414000D03*
Y424000D03*
X186500Y498000D03*
X144000Y501500D03*
X173600Y498800D03*
X169200Y482800D03*
X157100Y500000D03*
X144000Y493500D03*
Y486182D03*
X162000Y457600D03*
X161900Y463300D03*
X188500Y474500D03*
X186500Y513500D03*
X173700Y513900D03*
X144000Y517500D03*
X173500Y506000D03*
X186500D03*
Y519000D03*
X174900Y523300D03*
X156800Y515400D03*
Y506900D03*
X152700Y618803D03*
X170349Y619949D03*
X151432Y661741D03*
X148995Y658568D03*
X146800Y1018900D03*
X143900Y1022700D03*
X155000Y1130500D03*
Y1125000D03*
Y1120000D03*
X148300Y1465000D03*
X152500Y1456000D03*
X174500Y1503500D03*
Y1509500D03*
X174000Y1515500D03*
Y1522000D03*
X148000Y1550000D03*
X170000Y1541000D03*
X148000Y1558000D03*
Y1528000D03*
Y1542000D03*
X168500Y1533500D03*
X170000Y1555000D03*
X161400Y1543500D03*
X150000Y1576000D03*
X156000Y1570000D03*
X154000Y1564000D03*
X170000Y1548500D03*
X169500Y1561500D03*
X161300Y1563100D03*
X148000Y1564000D03*
X156000Y1576000D03*
X168500Y1526000D03*
X166898Y1567102D03*
X150000Y1570000D03*
X156000Y1582000D03*
X156500Y1591000D03*
X150500Y1582000D03*
Y1591000D03*
X172000Y1606000D03*
X182500Y1599400D03*
X146000Y1612000D03*
X148000Y1606000D03*
X182500Y1592000D03*
X164000Y1606000D03*
X156500Y1600000D03*
X156000Y1606000D03*
X150500Y1600000D03*
X138500Y1606000D03*
X182500Y1584500D03*
X176000Y1646000D03*
X166000D03*
X158000D03*
X148000D03*
X176000Y1632000D03*
X178000Y1659500D03*
X167500Y1632500D03*
X170000Y1659500D03*
X149000Y1632500D03*
X159000D03*
Y1659500D03*
X148500Y1660000D03*
X190239Y447449D03*
X195600Y447500D03*
X192000Y490000D03*
Y498000D03*
X200300Y498100D03*
X199500Y489400D03*
X189900Y467500D03*
Y460500D03*
X190400Y453500D03*
X195000Y467500D03*
X194500Y474500D03*
X195000Y460500D03*
X195500Y453500D03*
X192000Y513500D03*
Y506000D03*
X190200Y523400D03*
X201089Y523500D03*
X193600Y519100D03*
X200100Y513600D03*
X199800Y506000D03*
X201200Y519200D03*
G54D13*
X15906Y48110D03*
Y58110D03*
Y68110D03*
Y78110D03*
Y88110D03*
Y481339D03*
Y491339D03*
Y501339D03*
Y511339D03*
Y741181D03*
Y751181D03*
Y761181D03*
Y771181D03*
Y781181D03*
Y1187323D03*
Y1197323D03*
Y1207323D03*
Y1217323D03*
Y1227323D03*
Y1447165D03*
Y1457165D03*
Y1467165D03*
Y1477165D03*
Y1487165D03*
Y1880394D03*
Y1890394D03*
Y1900394D03*
Y1910394D03*
Y1920394D03*
X138937Y1778819D03*
X128937D03*
X118937D03*
X165000Y1370500D03*
Y1390500D03*
Y1380500D03*
G54D25*
X80709Y204409D03*
Y224409D03*
Y244409D03*
Y256929D03*
Y266929D03*
Y276929D03*
Y286929D03*
X110709Y204409D03*
Y214409D03*
Y224409D03*
Y234409D03*
Y244409D03*
X100709Y204409D03*
Y214409D03*
Y224409D03*
Y234409D03*
Y244409D03*
X90709Y214409D03*
Y234409D03*
X110709Y256929D03*
Y266929D03*
X100709Y256929D03*
Y266929D03*
X90709Y256929D03*
Y266929D03*
X110709Y276929D03*
Y286929D03*
X100709Y276929D03*
Y286929D03*
X90709Y276929D03*
Y286929D03*
X179606Y204409D03*
Y214409D03*
Y224409D03*
Y234409D03*
Y244409D03*
X169606Y204409D03*
Y214409D03*
Y224409D03*
Y234409D03*
Y244409D03*
X159606Y214409D03*
Y234409D03*
X149606Y204409D03*
Y224409D03*
Y244409D03*
X179606Y256929D03*
Y266929D03*
X169606Y256929D03*
Y266929D03*
X159606Y256929D03*
Y266929D03*
X149606Y256929D03*
Y266929D03*
X179606Y276929D03*
Y286929D03*
X169606Y276929D03*
Y286929D03*
X159606Y276929D03*
Y286929D03*
X149606Y276929D03*
Y286929D03*
G54D20*
X30000Y782000D03*
X26600Y1570100D03*
X26700Y1579800D03*
X79122Y565700D03*
X79458Y578758D03*
X44000Y782000D03*
X37900Y1570000D03*
X38300Y1579600D03*
X131800Y289700D03*
X130900Y259100D03*
X87595Y581300D03*
X141300Y298100D03*
X188300Y368600D03*
X181800Y369000D03*
X181100Y364050D03*
X182600Y546900D03*
X141800Y559250D03*
X153500Y574359D03*
X140700Y576600D03*
G54D12*
X8594Y6500D03*
X31500Y5500D03*
X20000Y6000D03*
X17000Y36500D03*
X32000Y40000D03*
X5594Y87000D03*
Y53500D03*
X29500Y53000D03*
X26000Y87000D03*
X30800Y130300D03*
X4594Y120500D03*
X34400Y95300D03*
X14000Y141000D03*
X23500Y124000D03*
X15000Y131500D03*
X14500Y100500D03*
Y112500D03*
X4500Y105500D03*
X5000Y137500D03*
X22500Y190000D03*
X29700Y191400D03*
X5594Y153500D03*
X4594Y187500D03*
X16500Y175000D03*
X27000Y182000D03*
X14000Y184000D03*
X4500Y170500D03*
X21500Y241500D03*
X4594Y234000D03*
X24000Y212000D03*
X29000Y200500D03*
X13000Y244000D03*
X13500Y230500D03*
X13000Y212500D03*
X5000Y221000D03*
X12500Y197500D03*
X4500Y202500D03*
X5094Y278000D03*
X6094Y257000D03*
X13500Y279000D03*
X34200Y284800D03*
X13500Y295000D03*
X5500Y295500D03*
X12500Y266500D03*
X5500Y269500D03*
X5000Y247500D03*
X32600Y290500D03*
X19721Y267203D03*
X5594Y312000D03*
X5304Y342500D03*
X4900Y328000D03*
X13500Y303500D03*
X29500Y343500D03*
X13000Y321000D03*
X23100Y342400D03*
X32675Y299500D03*
X4594Y396500D03*
X6500Y375000D03*
X27000Y371000D03*
X4800Y356200D03*
X23400Y353500D03*
X23700Y363900D03*
X29500Y364500D03*
X27000Y377500D03*
Y384000D03*
Y389500D03*
X34000Y448000D03*
X4594Y421000D03*
X5304Y444500D03*
Y440500D03*
X5000Y408500D03*
X5304Y434500D03*
X29500Y410500D03*
X26500Y440000D03*
X26000Y432500D03*
X23800Y410700D03*
X5094Y469500D03*
X5000Y495000D03*
X4700Y458200D03*
X5000Y486500D03*
X33200Y468900D03*
X14000Y476000D03*
X28800Y533700D03*
X5304Y548800D03*
Y528900D03*
X5094Y600000D03*
X34100Y566600D03*
X13510Y597990D03*
X5094Y574500D03*
X29500Y586500D03*
X14000Y614000D03*
X4594Y625000D03*
X18000Y608000D03*
X6000Y612000D03*
Y646000D03*
X26000Y656500D03*
X5594Y688500D03*
X5304Y661000D03*
X14000Y659000D03*
X23000Y677500D03*
X32000Y666000D03*
X28000Y706000D03*
X8000Y678000D03*
X31000Y700500D03*
X20000Y696000D03*
X6000Y698000D03*
Y706500D03*
X31000Y747000D03*
X22000Y746000D03*
X24000Y756000D03*
X27000Y750000D03*
X26000Y732000D03*
X18000Y724000D03*
Y732500D03*
Y712000D03*
X6000Y722000D03*
Y730500D03*
X4594Y749000D03*
Y714000D03*
X5594Y778000D03*
X6500Y799000D03*
X9500Y804000D03*
X16100Y794600D03*
X5594Y844500D03*
X6094Y819500D03*
X30500D03*
X10000Y811500D03*
X24000Y846000D03*
X24500Y853500D03*
X16000Y828000D03*
Y814000D03*
Y856000D03*
Y842000D03*
X32000Y858000D03*
Y844000D03*
X4500Y833500D03*
Y857500D03*
X26053Y828247D03*
X5094Y897500D03*
X5594Y869000D03*
X16000Y906000D03*
X32000Y886000D03*
Y872000D03*
X18000Y884000D03*
Y870000D03*
X5000Y883500D03*
X18500Y896500D03*
X23053Y861247D03*
X5304Y926000D03*
X4594Y954000D03*
X18000Y934000D03*
Y920000D03*
X16000Y962000D03*
Y948000D03*
X4500Y913000D03*
Y941500D03*
X34000Y944000D03*
Y934500D03*
X33500Y962500D03*
Y953000D03*
X26053Y938247D03*
X4594Y1013500D03*
X5594Y984500D03*
X28000Y992000D03*
X26000Y1010000D03*
X16000Y990000D03*
Y976000D03*
Y1014000D03*
Y1000000D03*
X4500Y970000D03*
Y997000D03*
X34000Y984000D03*
Y974500D03*
Y1008000D03*
X25053Y971247D03*
X4594Y1041500D03*
X6000Y1058000D03*
X33600Y1029900D03*
X16000Y1046000D03*
Y1032000D03*
X14000Y1060000D03*
X4500Y1029500D03*
X34000Y1017500D03*
X27553Y1029247D03*
X5094Y1074500D03*
X32000Y1114000D03*
X34000Y1102000D03*
Y1072000D03*
X28000D03*
X14000Y1074000D03*
Y1100000D03*
Y1086000D03*
X16000Y1110000D03*
X6000Y1096000D03*
X26100Y1088600D03*
X27218Y1097000D03*
X33550Y1080100D03*
X34000Y1144000D03*
X16000Y1124000D03*
Y1148000D03*
Y1134000D03*
Y1162000D03*
X6000Y1138000D03*
Y1118000D03*
Y1152000D03*
X26600Y1132400D03*
X24553Y1153247D03*
X5304Y1208000D03*
X4594Y1169500D03*
X24000Y1180000D03*
X16000Y1176000D03*
X5094Y1268500D03*
X8500Y1237000D03*
X30000Y1240000D03*
X16000Y1262000D03*
Y1244000D03*
X28000Y1266000D03*
X6000Y1252000D03*
X22000Y1232000D03*
X31500Y1222000D03*
X6500Y1302000D03*
X17700Y1283000D03*
X34000Y1312000D03*
X6000Y1318000D03*
X12000Y1274000D03*
Y1294000D03*
X28000Y1286000D03*
Y1300000D03*
Y1320000D03*
X19800Y1315400D03*
X13500Y1365000D03*
X8000Y1368000D03*
X5000Y1355000D03*
X30800Y1403900D03*
X31500Y1397500D03*
X5304Y1409400D03*
X4594Y1382000D03*
X7500Y1376500D03*
X32000Y1391500D03*
X4800Y1460700D03*
X4594Y1435500D03*
X34000Y1465900D03*
X5304Y1504100D03*
Y1522100D03*
X4600Y1484800D03*
X34000Y1477600D03*
X29500Y1495800D03*
X5304Y1576200D03*
Y1540500D03*
X26700Y1529800D03*
X26900Y1547900D03*
Y1559100D03*
X4594Y1607500D03*
X33100Y1587400D03*
X28000Y1596800D03*
X7500Y1640200D03*
X5304Y1659000D03*
X4700Y1676100D03*
X4594Y1632000D03*
X35500Y1670500D03*
X29000Y1671000D03*
X31400Y1648200D03*
X5304Y1723500D03*
X4900Y1708000D03*
X13100Y1728900D03*
X4594Y1691000D03*
X19542Y1710518D03*
X29100Y1721550D03*
X34000Y1691500D03*
X30000Y1731000D03*
X4594Y1775000D03*
Y1751000D03*
X12600Y1753800D03*
X13100Y1742600D03*
X12900Y1765200D03*
X14500Y1832500D03*
X12600Y1792800D03*
X12500Y1782500D03*
X22000Y1787800D03*
X4594Y1878500D03*
X14500Y1863500D03*
X5000Y1864100D03*
X18600Y1871400D03*
X4594Y1850000D03*
X15000Y1854900D03*
X27500Y1883500D03*
X14500Y1842000D03*
X28000Y1876500D03*
X29000Y1841000D03*
X13100Y1933900D03*
X24800Y1926500D03*
X5094Y1921000D03*
X4594Y1902000D03*
X35000Y1933500D03*
X27400Y1899400D03*
X35300Y1925300D03*
X34500Y1963200D03*
X16100Y1950700D03*
X5094Y1944500D03*
X15500Y1942500D03*
X4500Y1936000D03*
X6500Y1962000D03*
X25000Y1962500D03*
X12500Y1959000D03*
X63594Y7000D03*
Y25500D03*
X40594Y6000D03*
X49000Y18500D03*
X43000Y27000D03*
X64500Y40000D03*
X64000Y17000D03*
X53000Y5000D03*
X51500Y53000D03*
X74000Y60500D03*
X79000Y65500D03*
X75000Y67500D03*
X74000Y45000D03*
X85000D03*
X84500Y56500D03*
X63098Y119103D03*
X52000Y115600D03*
X62598Y141103D03*
X51700Y131700D03*
X59600Y125800D03*
X71000Y131859D03*
X37000Y124000D03*
X53000Y171500D03*
X51900Y145700D03*
X65000Y166300D03*
X60350Y151950D03*
X86000Y152000D03*
X69000Y153000D03*
X73500Y146000D03*
X39300Y181100D03*
X60800Y147700D03*
X63500Y179300D03*
X54200Y207850D03*
Y220700D03*
X51700Y234800D03*
X42500Y260200D03*
X36000Y260386D03*
X58936Y256289D03*
X52500Y248500D03*
X50800Y266400D03*
X51000Y529500D03*
X66000Y550500D03*
X71445Y532192D03*
X72397Y528297D03*
X74942Y530983D03*
X49700Y568900D03*
X36000Y554000D03*
X65000Y561500D03*
X78400Y583700D03*
X70350Y558850D03*
X54600Y573400D03*
X82000Y652000D03*
X66200Y653500D03*
X84200Y643865D03*
X71800Y701300D03*
X64000Y666600D03*
X52500Y682500D03*
X53000Y695100D03*
X39800Y681400D03*
X50000Y712500D03*
Y749000D03*
X40000Y746500D03*
X36000Y730000D03*
X46000Y726000D03*
X71500Y735500D03*
X73500Y732000D03*
X82000Y806500D03*
X42000Y802000D03*
Y788000D03*
X47600Y796800D03*
X79000Y857000D03*
X81500Y837500D03*
X82500Y814000D03*
X48000Y816000D03*
X38000Y834000D03*
Y820000D03*
X46000Y848000D03*
Y834000D03*
X78300Y832600D03*
X77600Y849100D03*
X87000Y839500D03*
X48100Y853400D03*
X45600Y827500D03*
X59500Y881600D03*
X57500Y890300D03*
X37500Y912000D03*
Y907500D03*
X77000Y871500D03*
X62500Y862000D03*
X61500Y876500D03*
X78000Y878500D03*
X77500Y907000D03*
X85500Y903000D03*
X78300Y893900D03*
X77000Y863000D03*
X83400Y878600D03*
X47000Y877600D03*
X40900Y901500D03*
X86500Y932000D03*
X61500Y938500D03*
X81500Y940000D03*
X75500Y936500D03*
X69500Y939000D03*
X55500Y955500D03*
X56500Y940000D03*
X62500Y924500D03*
X70000Y914500D03*
Y925500D03*
X76500Y927000D03*
X85500Y915000D03*
X77500Y917000D03*
X54300Y915500D03*
X70800Y990500D03*
X87000Y997500D03*
X55500Y968000D03*
X76400Y999100D03*
X57500Y987800D03*
Y984300D03*
X83500Y976300D03*
Y972800D03*
X83000Y979800D03*
X53800Y1006200D03*
X56000Y1021500D03*
X54500Y1035500D03*
X64500Y1099000D03*
X37500Y1118900D03*
X40000Y1136000D03*
Y1156000D03*
X58000Y1206000D03*
X46000Y1218000D03*
X60000Y1194000D03*
X61000Y1173000D03*
X54000Y1184000D03*
X44000Y1194000D03*
X42000Y1242000D03*
X50000Y1244000D03*
X42000Y1266000D03*
X58000Y1250000D03*
Y1222000D03*
X39500Y1231000D03*
X51800Y1231600D03*
X50100Y1261500D03*
X42000Y1290000D03*
X50000Y1318000D03*
X40000Y1278000D03*
Y1298000D03*
X44000Y1306000D03*
X58000Y1312000D03*
Y1292000D03*
Y1272000D03*
X52000Y1296300D03*
X61000Y1363500D03*
X52500Y1368500D03*
X39000Y1333500D03*
X44000Y1326000D03*
Y1340000D03*
X54000Y1330000D03*
X72000Y1360000D03*
X83800Y1365900D03*
X84000Y1352000D03*
X39400Y1381300D03*
X81500Y1382000D03*
Y1416500D03*
Y1404000D03*
X71800Y1373900D03*
X83800Y1391900D03*
X70500Y1378500D03*
X69400Y1402900D03*
X39500Y1407900D03*
X55600Y1381700D03*
X48900Y1390500D03*
X60900D03*
X56700Y1400100D03*
X60600Y1423600D03*
X68800Y1417800D03*
X58800Y1412400D03*
X49000Y1413300D03*
X72900Y1393600D03*
X74900Y1408800D03*
X75600Y1420300D03*
X44500Y1380500D03*
X45500Y1400000D03*
X61500Y1380000D03*
X70400Y1444500D03*
X79000Y1436400D03*
X76200Y1430700D03*
X66500Y1433500D03*
X53100Y1430700D03*
X42600Y1444200D03*
X49100Y1448400D03*
X68500Y1454600D03*
X74500Y1461800D03*
X72300Y1469800D03*
X59000Y1444500D03*
X77000Y1449000D03*
X59000Y1472000D03*
X58100Y1459300D03*
X80000Y1472000D03*
X83200Y1455500D03*
X45000Y1428000D03*
X63000Y1482300D03*
X36400Y1523400D03*
X42700Y1500000D03*
X72700Y1480500D03*
X46500Y1484900D03*
X64100Y1495400D03*
X73000Y1491200D03*
X43300Y1518500D03*
X49500Y1505000D03*
X45400Y1523800D03*
X46600Y1541100D03*
X45300Y1563600D03*
X45900Y1532800D03*
X38800Y1541700D03*
X38300Y1561800D03*
X44400Y1592100D03*
X43500Y1620700D03*
X42700Y1606000D03*
X38400Y1596700D03*
X42500Y1673000D03*
X44500Y1678000D03*
X43200Y1634800D03*
X43600Y1668300D03*
X43300Y1646600D03*
X75500Y1679000D03*
X86000D03*
X42500Y1699500D03*
X45500Y1690000D03*
X41500Y1692000D03*
X40300Y1703900D03*
X44100Y1685200D03*
X44600Y1724400D03*
X44900Y1706800D03*
X56000Y1695000D03*
Y1704500D03*
Y1712500D03*
X55500Y1723500D03*
X69000Y1684500D03*
X80500D03*
X62500Y1691500D03*
X65000Y1724000D03*
X62500Y1709000D03*
X72500Y1717000D03*
Y1699000D03*
X62500Y1700000D03*
X60000Y1730000D03*
X86500Y1713610D03*
Y1700110D03*
Y1726000D03*
X52500Y1756000D03*
X53000Y1750500D03*
X36700Y1764700D03*
X56500Y1769300D03*
X44900Y1740300D03*
X64500Y1758500D03*
X55500Y1735500D03*
X65000Y1735000D03*
X79000Y1766500D03*
X65000Y1749000D03*
Y1768000D03*
Y1742500D03*
X71500Y1760000D03*
X72500Y1733000D03*
X87000Y1774110D03*
X81000Y1802000D03*
X73000Y1813000D03*
X64500Y1821500D03*
Y1812000D03*
Y1801500D03*
X65000Y1790000D03*
X72500Y1830000D03*
X72000Y1798000D03*
X86500Y1793110D03*
X39700Y1869700D03*
X46700Y1857700D03*
X46500Y1850200D03*
X44500Y1833500D03*
X46500Y1844000D03*
Y1865500D03*
X55900Y1881500D03*
X62000Y1877000D03*
X75500Y1838500D03*
X63500Y1863000D03*
Y1856000D03*
X64000Y1844500D03*
Y1834000D03*
X73000Y1847000D03*
X85100Y1844500D03*
X85700Y1852300D03*
X45100Y1933400D03*
X54500Y1889500D03*
X63500Y1928000D03*
X61500Y1922500D03*
X46000Y1923000D03*
X57900Y1899800D03*
X65300Y1886600D03*
X38700Y1893800D03*
X41500Y1889500D03*
X60300Y1892300D03*
X47000Y1886200D03*
X79900Y1923000D03*
X54000Y1928500D03*
X36500Y1900500D03*
X63500Y1963000D03*
X63594Y1935500D03*
X61600Y1954700D03*
X41100Y1957500D03*
X55300Y1959100D03*
X43500Y1945000D03*
X49053Y1951747D03*
X135000Y50000D03*
Y70000D03*
X128500Y89000D03*
X118000Y54500D03*
X124000Y74500D03*
X105000Y55000D03*
Y45000D03*
X95000D03*
X115000D03*
X125000D03*
X135000D03*
X92500Y73000D03*
X137200Y123600D03*
X127700Y119200D03*
X128700Y104200D03*
X131000Y138100D03*
X118000Y124500D03*
X119000Y109500D03*
X118000Y142500D03*
X95000Y143000D03*
X105000D03*
X95000Y125000D03*
X105000D03*
X95000Y134000D03*
X129000Y160100D03*
X137900Y171400D03*
X131000Y150100D03*
X118000Y154500D03*
X95000Y155000D03*
X105000D03*
X105500Y390000D03*
Y406500D03*
X101500D03*
X107000Y426500D03*
X98000D03*
X102500D03*
X110500Y406500D03*
X108100Y477650D03*
X117000Y530000D03*
X108900Y541300D03*
X102700Y541000D03*
X106300Y553200D03*
X124200Y568400D03*
X119800Y568300D03*
X133500Y575500D03*
X137000Y589900D03*
X133500Y582000D03*
X134600Y586700D03*
X88000Y586500D03*
X101000Y583000D03*
X96000Y588000D03*
X89000Y595000D03*
X87000Y591000D03*
X103100Y587600D03*
X135000Y561500D03*
X121000Y581500D03*
X124900Y582000D03*
X91300Y577000D03*
X92200Y553800D03*
X87000Y648000D03*
X134600Y665600D03*
X87310Y676796D03*
X130000Y700500D03*
X122500D03*
X114500D03*
X105500Y702500D03*
X93000Y698500D03*
X88500Y700000D03*
X98000Y698500D03*
Y703000D03*
X129800Y696800D03*
X98000Y674327D03*
X102913Y673973D03*
X107113Y674001D03*
X108500Y695500D03*
X103500D03*
X115000Y704500D03*
X99001Y694866D03*
X125000Y734000D03*
X116500Y752000D03*
X125000Y751000D03*
X125500Y741500D03*
X130000Y736500D03*
Y753000D03*
Y746000D03*
X119500Y757500D03*
Y746500D03*
Y739500D03*
X113500Y729000D03*
Y736000D03*
Y747000D03*
Y756000D03*
Y721000D03*
X106000Y709000D03*
X98000Y708000D03*
X125000Y758500D03*
X120500Y732500D03*
X120000Y717500D03*
X123000Y808500D03*
X114500Y805500D03*
X123000Y800000D03*
X122500Y792500D03*
X114000Y800000D03*
X113500Y792500D03*
X130000Y800000D03*
X129500Y792500D03*
X121500Y783500D03*
X121000Y776000D03*
X129500Y782000D03*
X129000Y774500D03*
X130000Y764000D03*
X115200Y784200D03*
X115000Y773200D03*
X121000Y767900D03*
X95500Y841500D03*
X124500Y858000D03*
X123500Y842500D03*
Y816000D03*
X115000Y813000D03*
X129200Y830400D03*
X129800Y813500D03*
X124500Y825100D03*
X134500Y840500D03*
X90500Y831500D03*
X118700Y840700D03*
X137500Y903000D03*
X135500Y909000D03*
X124000D03*
X113500Y909500D03*
X103500D03*
X94000Y910500D03*
X116053Y903247D03*
X127000Y903000D03*
X90000Y893000D03*
X102500Y893500D03*
X117500Y893000D03*
X135000D03*
X134500Y885500D03*
X137500Y876500D03*
X125000Y868500D03*
X107000Y903000D03*
X124500Y876500D03*
X126000Y892500D03*
X96053Y903247D03*
X125500Y944000D03*
X105000Y958000D03*
X96500Y916500D03*
X107000Y918000D03*
X135000D03*
X135500Y927500D03*
X115000Y920000D03*
X125500D03*
X126000Y930000D03*
X115500D03*
X99000Y953000D03*
X88500Y940500D03*
X120000Y916000D03*
X126000Y954000D03*
X124618Y959244D03*
X110000Y949500D03*
X117529Y948844D03*
X93000Y925500D03*
X133500Y938000D03*
X125400Y983600D03*
Y992000D03*
X134000Y990500D03*
X125000Y967000D03*
X130500Y966000D03*
X124000Y971500D03*
X117000Y1008500D03*
X105500Y996000D03*
X95500Y999000D03*
X106500Y1008500D03*
X104000Y1014000D03*
X119000Y975000D03*
X136500Y967000D03*
X108500Y964000D03*
Y971000D03*
X97300Y990800D03*
X114800Y1005000D03*
X94000Y971800D03*
X135000Y975500D03*
X110500Y1041500D03*
X111500Y1030000D03*
Y1020000D03*
X110500Y1064500D03*
Y1051000D03*
X103500Y1042000D03*
Y1028500D03*
X116500Y1049000D03*
Y1035500D03*
Y1062500D03*
X117500Y1023500D03*
X104000Y1062500D03*
Y1049500D03*
X120000Y1108000D03*
Y1102000D03*
X115000Y1108500D03*
X110500Y1112000D03*
X103500Y1073500D03*
X104500Y1095000D03*
X116500Y1076000D03*
X109000Y1083500D03*
X118500Y1166000D03*
X105000Y1196000D03*
X119300Y1191400D03*
X119500Y1177500D03*
Y1205500D03*
X92000Y1214500D03*
X104500Y1208000D03*
X105000Y1181000D03*
X94000Y1189000D03*
X91500Y1200000D03*
X99000Y1265500D03*
X119000Y1269000D03*
X117500Y1251000D03*
X112000Y1250500D03*
Y1244500D03*
X119300Y1245400D03*
Y1219400D03*
X119500Y1231500D03*
X124000Y1270000D03*
X104500Y1219500D03*
X92000Y1254000D03*
X103500Y1229000D03*
X92000Y1241500D03*
X103000Y1244900D03*
X91500Y1229000D03*
X99500Y1310000D03*
Y1294000D03*
X98000Y1282000D03*
X123800Y1283900D03*
X113800Y1287900D03*
X114000Y1274000D03*
X123800Y1311900D03*
X124000Y1298000D03*
X114000Y1318000D03*
X92000Y1295500D03*
X91500Y1314500D03*
X114500Y1296500D03*
X97800Y1327900D03*
X123800Y1337900D03*
X124000Y1324000D03*
X113800Y1331900D03*
X115800Y1363900D03*
X116000Y1350000D03*
X123800Y1365900D03*
X124000Y1352000D03*
X114500Y1370500D03*
X93800Y1353900D03*
X94000Y1340000D03*
Y1366000D03*
X90800Y1331200D03*
X100500Y1384500D03*
Y1389000D03*
X124000Y1376500D03*
X125000Y1398500D03*
X100860Y1402260D03*
X111000Y1394000D03*
X114000Y1376000D03*
X93800Y1379900D03*
Y1393200D03*
X93600Y1407100D03*
X97500Y1412000D03*
X89700Y1409700D03*
X110000Y1418000D03*
X125100Y1402500D03*
X137000Y1429200D03*
X126600Y1461500D03*
X133500Y1467100D03*
X132200Y1424800D03*
X94000Y1427800D03*
X87200Y1431900D03*
X87700Y1446500D03*
X87300Y1436000D03*
X95500Y1468000D03*
X103700Y1470300D03*
X113024Y1452079D03*
X117122Y1448001D03*
X117195Y1456070D03*
X121338Y1452021D03*
X117024Y1452000D03*
X97000Y1503100D03*
X93500Y1482700D03*
X99170Y1485790D03*
X117500Y1679000D03*
X125000D03*
X107500D03*
X122000Y1685500D03*
X91000Y1685000D03*
X103000D03*
X112500D03*
X108500Y1727000D03*
X98500Y1717000D03*
Y1696500D03*
X99000Y1707000D03*
X97500Y1679500D03*
X109500Y1719500D03*
X110000Y1709500D03*
X109500Y1699000D03*
X119500Y1710110D03*
Y1696610D03*
Y1725110D03*
X111500Y1768500D03*
X117500Y1732000D03*
X119500Y1760000D03*
X97500Y1775500D03*
X108268Y1777300D03*
X119500Y1747110D03*
X138000Y1824000D03*
X110500Y1801000D03*
X88500Y1785000D03*
X97500Y1796000D03*
X98000Y1786000D03*
X107768Y1789110D03*
X120000Y1811500D03*
X119500Y1796500D03*
X114000Y1843500D03*
X97000Y1850500D03*
X99500Y1862500D03*
X106500D03*
X114500D03*
X122500D03*
X120500Y1836500D03*
Y1850500D03*
X108500Y1851610D03*
X118000Y1922000D03*
X91100Y1922800D03*
X128900Y1923300D03*
X104600Y1923400D03*
X133500Y1906500D03*
X149500Y52000D03*
X184000Y55500D03*
X174000D03*
X164000D03*
X153000Y90500D03*
X154000Y75500D03*
X145000Y45000D03*
X155000D03*
X165000D03*
X175000D03*
X185000D03*
X180500Y112000D03*
X186000Y143000D03*
X187500Y130500D03*
X167000D03*
X176000Y131000D03*
X165500Y95500D03*
X174500Y143500D03*
X171500Y105500D03*
X170500Y120500D03*
X146500Y131859D03*
X154000Y105500D03*
X147600Y150900D03*
X165300Y145200D03*
X173500Y151500D03*
X185500D03*
X138800Y162100D03*
X187500Y338000D03*
X184500Y325500D03*
X186600Y425750D03*
X142000Y478500D03*
X147000Y529900D03*
X144600Y533800D03*
X147500Y551500D03*
X156300Y552100D03*
X142500Y550000D03*
X180500Y595000D03*
X171600Y595400D03*
X145800Y594400D03*
X145500Y604000D03*
X150500Y596000D03*
X142100Y581400D03*
X167300Y653800D03*
X159700Y652000D03*
X175800Y617635D03*
X164950Y615700D03*
X180500Y627771D03*
X165600Y630269D03*
X165433Y692372D03*
X185000Y673500D03*
X188100Y689100D03*
X161000Y674000D03*
X157500Y664500D03*
X176000Y679000D03*
Y665500D03*
X147000Y703000D03*
X149000Y677000D03*
X162300Y659100D03*
X183500Y698000D03*
X184700Y663900D03*
X165500Y677500D03*
X146000Y755000D03*
X184500Y708500D03*
X166000Y751500D03*
X170000Y745500D03*
X161600Y739800D03*
X161500Y747500D03*
X146000Y726000D03*
X165900Y717300D03*
X181000Y729000D03*
Y715500D03*
X182500Y758500D03*
Y745000D03*
X146000Y738000D03*
X172000Y757500D03*
X181500Y738500D03*
X169100Y722100D03*
X175100Y710000D03*
X169000Y795500D03*
X163500Y805500D03*
X178000Y797500D03*
X146000Y765500D03*
Y796500D03*
Y782500D03*
X187900Y785300D03*
X175000Y786500D03*
X166000Y760000D03*
X166500Y775500D03*
X161500Y759000D03*
Y768000D03*
Y778000D03*
X173500Y777500D03*
Y764000D03*
X181700Y768400D03*
X165000Y786000D03*
X171500Y819500D03*
X177500Y812000D03*
X146500D03*
X146000Y824000D03*
X177500Y826500D03*
X180000Y856000D03*
X162000Y817500D03*
X174000Y834500D03*
X168000Y830000D03*
X145500Y856500D03*
X140500Y846500D03*
X157500Y858000D03*
X185000Y843500D03*
X145500Y885000D03*
X180000Y872500D03*
X179500Y884000D03*
X179900Y900900D03*
X143000Y910500D03*
X146000Y893000D03*
X184500Y879000D03*
Y865500D03*
X154700Y909700D03*
X156300Y877200D03*
X156500Y889000D03*
X187000Y891000D03*
X153500Y941000D03*
X141000Y938500D03*
X144000Y919500D03*
Y929000D03*
X180000Y960400D03*
X179900Y925700D03*
X179800Y941400D03*
X180000Y912500D03*
X154500Y926500D03*
X185000Y917500D03*
X182000Y950500D03*
X163100Y978600D03*
X163200Y985200D03*
X149800Y1008700D03*
X174000Y1012400D03*
X179000Y1005000D03*
X180500Y973200D03*
X184000Y987500D03*
X155500Y1030000D03*
X153500Y1033500D03*
X151500Y1030500D03*
X166300Y1021300D03*
X182500Y1041500D03*
X183500Y1065500D03*
X159500Y1062000D03*
X163000Y1042500D03*
X182000Y1029500D03*
Y1016000D03*
X171000Y1046000D03*
Y1032500D03*
X175000Y1059000D03*
X160500Y1053500D03*
X181000Y1051000D03*
X164700Y1033600D03*
X176000Y1018500D03*
X171000Y1068000D03*
X166000Y1080000D03*
X173000Y1082000D03*
X165000Y1097000D03*
X181000Y1098500D03*
X175000Y1072500D03*
X160500Y1067000D03*
X187500Y1103500D03*
Y1090000D03*
X170000Y1103000D03*
Y1089500D03*
X157000Y1101500D03*
X159500Y1087500D03*
X181000Y1112500D03*
Y1079500D03*
X154600Y1111000D03*
X158500Y1075800D03*
X158595Y1110789D03*
X147500Y1165500D03*
X177102Y1129800D03*
X171502Y1129547D03*
X147500Y1186000D03*
X178644Y1202519D03*
X163344Y1181200D03*
X161500Y1227500D03*
X147500Y1221500D03*
X146500Y1241500D03*
X147000Y1265500D03*
X183500Y1241500D03*
X165000Y1264500D03*
X147500Y1288000D03*
Y1311000D03*
X164500Y1299500D03*
X147500Y1332000D03*
X147000Y1348000D03*
X147500Y1366500D03*
X147000Y1377000D03*
X146500Y1417619D03*
Y1397100D03*
X155900D03*
X173375Y1432500D03*
X149686Y1460007D03*
X169000Y1426750D03*
X141500Y1673000D03*
X139000Y1696500D03*
Y1712500D03*
X138500Y1727500D03*
X181500Y1716500D03*
X158500D03*
X167500Y1716000D03*
X182000Y1726000D03*
Y1704000D03*
X168500Y1705000D03*
X158500D03*
X184500Y1696500D03*
X163000Y1697000D03*
X174268Y1697110D03*
X152000D03*
Y1710610D03*
Y1725610D03*
X185000Y1738500D03*
X183600Y1765100D03*
X169000Y1781500D03*
X162500Y1773000D03*
X152500Y1771110D03*
X173268Y1776000D03*
X139000Y1800500D03*
X156500Y1782000D03*
X155500Y1798500D03*
X166500Y1798000D03*
X179000Y1798500D03*
X185500Y1804500D03*
X186000Y1790000D03*
X162000D03*
X172768Y1790110D03*
X152000D03*
X139000Y1851000D03*
X138500Y1839500D03*
X185000Y1852500D03*
X161500D03*
X183100Y1838300D03*
X160500Y1877500D03*
X152500Y1883100D03*
X173000Y1852610D03*
X151500Y1851110D03*
X184500Y1920500D03*
X170000D03*
X161000Y1901500D03*
X162100Y1912000D03*
X151900Y1891400D03*
X146300Y1913700D03*
X142400Y1923800D03*
X176700Y1923900D03*
X177700Y1912800D03*
X157900Y1923100D03*
X194000Y55500D03*
X195000Y45000D03*
X200000Y55000D03*
Y65000D03*
Y75000D03*
Y85000D03*
X190500Y105000D03*
X189500Y120000D03*
X200000Y100000D03*
Y120000D03*
Y140000D03*
X191900Y167700D03*
X191700Y186500D03*
X201089Y181700D03*
X197500Y151500D03*
X201500Y165000D03*
X191900Y244600D03*
X191800Y234900D03*
Y221100D03*
X191600Y206900D03*
X201500Y208000D03*
X201000Y222500D03*
X200500Y235000D03*
Y195900D03*
X202000Y295000D03*
Y274000D03*
Y254000D03*
X201089Y282600D03*
X202000Y264000D03*
Y340000D03*
Y328000D03*
X201089Y305500D03*
Y315500D03*
X201500Y397500D03*
Y378000D03*
X202000Y366500D03*
Y353000D03*
X192600Y392600D03*
X192471Y397355D03*
X201089Y388400D03*
X200500Y437500D03*
X201000Y430500D03*
X201089Y407000D03*
X200000Y420500D03*
X192400Y401900D03*
X192300Y410950D03*
X192409Y417655D03*
X201500Y544500D03*
X201089Y529500D03*
X201500Y552500D03*
X192400Y529400D03*
X191900Y538200D03*
X201500Y535000D03*
X192000Y543500D03*
X190500Y550500D03*
X202000Y578000D03*
Y586000D03*
Y595000D03*
X193700D03*
X194400Y586000D03*
X201089Y558000D03*
X201500Y564000D03*
X201089Y570600D03*
X202000Y607500D03*
X196500Y641500D03*
X192600Y633000D03*
X201500Y621500D03*
X202000Y650500D03*
X194000Y628500D03*
Y615000D03*
X192500Y645000D03*
X202210Y638500D03*
X195000Y670000D03*
X197500Y685000D03*
X197000Y704000D03*
X202000Y676500D03*
X192500Y658500D03*
X191500Y692500D03*
X193100Y679000D03*
X201500Y691500D03*
X202500Y666000D03*
X196000Y718500D03*
X195500Y739000D03*
X197500Y753000D03*
X202000Y710000D03*
Y740500D03*
X191500Y724000D03*
Y710500D03*
Y746500D03*
X201500Y726500D03*
X202500Y755500D03*
X196000Y789500D03*
X196500Y797000D03*
X202000Y765000D03*
Y786000D03*
Y807500D03*
X191500Y760000D03*
X194500Y782500D03*
Y769000D03*
X201500Y777000D03*
X201389Y797000D03*
X196800Y828500D03*
X197000Y815000D03*
X190000Y823500D03*
X190500Y831000D03*
X202000Y859500D03*
X201500Y835500D03*
X192500Y853000D03*
Y839500D03*
X202500Y822000D03*
Y846500D03*
X202000Y890000D03*
X192000Y879000D03*
Y865500D03*
X194000Y907000D03*
Y893500D03*
X202210Y903500D03*
X202000Y875000D03*
X202500Y945500D03*
X202000Y918000D03*
X192000Y934500D03*
Y921000D03*
Y962000D03*
Y948500D03*
X202500Y962000D03*
X201500Y931500D03*
X202500Y1006000D03*
Y977500D03*
X192500Y985500D03*
Y972000D03*
X195500Y1001000D03*
X201500Y991000D03*
X190000Y1052000D03*
X202000Y1037000D03*
X195500Y1014500D03*
X193500Y1042500D03*
Y1029000D03*
X195000Y1061000D03*
X202000Y1052000D03*
X201500Y1019000D03*
X195000Y1086500D03*
X194500Y1100500D03*
X201389Y1067000D03*
X195000Y1074500D03*
X201000Y1106500D03*
Y1093000D03*
X201500Y1082500D03*
X195000Y1112000D03*
X201500Y1147000D03*
X202000Y1212000D03*
X202500Y1179000D03*
X202000Y1246000D03*
X191800Y1280900D03*
X201500Y1306500D03*
X202500Y1280000D03*
X201500Y1359500D03*
Y1350000D03*
X201700Y1388300D03*
X201500Y1413000D03*
X202400Y1444000D03*
X201389Y1425500D03*
X202210Y1462000D03*
X194500Y1510000D03*
Y1505500D03*
X192500Y1543500D03*
Y1554000D03*
Y1533000D03*
Y1562500D03*
X196500Y1572000D03*
Y1586000D03*
Y1595000D03*
X192500Y1617000D03*
Y1626500D03*
X196500Y1606500D03*
X192500Y1634000D03*
Y1670500D03*
Y1664000D03*
Y1653000D03*
Y1648000D03*
X192650Y1641500D03*
X198500Y1713500D03*
X198000Y1691500D03*
X197500Y1776500D03*
X198000Y1754000D03*
Y1735500D03*
Y1818500D03*
X197500Y1800500D03*
X198500Y1859500D03*
X198000Y1838500D03*
X195000Y1874000D03*
X200000Y1882000D03*
X200500Y1876500D03*
X201500Y1900500D03*
X190500Y1924000D03*
X201000Y1923000D03*
X195500Y1905000D03*
X201200Y1890500D03*
X201100Y1908800D03*
G54D18*
X15906Y521339D03*
G54D24*
X80709Y161889D03*
Y171889D03*
Y181889D03*
Y191889D03*
Y214409D03*
Y234409D03*
X110709Y161889D03*
Y171889D03*
X100709Y161889D03*
Y171889D03*
X90709Y161889D03*
Y171889D03*
X110709Y181889D03*
Y191889D03*
X100709Y181889D03*
Y191889D03*
X90709Y181889D03*
Y191889D03*
Y204409D03*
Y224409D03*
Y244409D03*
X179606Y161889D03*
Y171889D03*
X169606Y161889D03*
Y171889D03*
X159606Y161889D03*
Y171889D03*
X149606Y161889D03*
Y171889D03*
X179606Y181889D03*
Y191889D03*
X169606Y181889D03*
Y191889D03*
X159606Y181889D03*
Y191889D03*
X149606Y181889D03*
Y191889D03*
X159606Y204409D03*
Y224409D03*
Y244409D03*
X149606Y214409D03*
Y234409D03*
G54D11*
X29921Y24803D03*
Y111417D03*
Y458031D03*
Y544646D03*
Y717874D03*
Y804488D03*
X30000Y1164000D03*
X29921Y1250630D03*
Y1423858D03*
Y1510472D03*
Y1857086D03*
Y1943701D03*
G54D21*
X47244Y68110D03*
Y501338D03*
Y761181D03*
Y1207323D03*
Y1467165D03*
Y1900393D03*
G54D22*
X80709Y119409D03*
Y329409D03*
X149606Y119409D03*
Y329409D03*
G54D23*
X80709Y139409D03*
Y309409D03*
X149606Y139409D03*
Y309409D03*
G54D29*
X111500Y390000D03*
X101300Y390100D03*
X111200Y426400D03*
G54D10*
X-222440Y19685D03*
Y1948818D03*
X643700Y19685D03*
Y1948818D03*
G54D26*
X69800Y574200D03*
X180850Y348800D03*
X188500Y364100D03*
G54D27*
X69100Y698006D03*
X74100Y669398D03*
X78494Y697835D03*
X79044Y1144112D03*
X66000Y1149500D03*
X74000Y1132000D03*
X77293Y1129729D03*
X134100Y674500D03*
X119000Y673300D03*
X124800Y696600D03*
%LPC*%
G75*
G54D30*
G01X-448201Y-66763D02*
X-480201D01*
G01X-448201Y-82763D02*
Y-162763D01*
G01Y-118263D02*
X752899D01*
G01X-448201Y-162763D02*
X752899D01*
G01X-452201Y-66763D02*
G02I-12000J0D01*
G01X-457351D02*
G02I-6850J0D01*
G01X-464201Y-82763D02*
Y-50763D01*
G01X-448201Y-82763D02*
X752899D01*
G01X-34601D02*
Y-162763D01*
G01X102899Y-82763D02*
Y-162763D01*
G01X217899Y-82763D02*
Y-162763D01*
G01X385399Y-82763D02*
Y-162763D01*
G01X555399Y-82763D02*
Y-162763D01*
G01X752899Y-82763D02*
Y-162763D01*
G01X780899Y-66763D02*
G02I-12000J0D01*
G01X775749D02*
G02I-6850J0D01*
G01X768899Y-82763D02*
Y-50763D01*
G01X784899Y-66763D02*
X752899D01*
G54D31*
G01X-430254Y-152763D02*
Y-135263D01*
G01X-421958D02*
X-430254Y-146055D01*
G01X-420648Y-152763D02*
X-426543Y-141097D01*
G01X-412973Y-152763D02*
Y-135263D01*
X-402929Y-152763D01*
Y-135263D01*
G01X-390451Y-152763D02*
X-392198Y-152471D01*
X-393726Y-151305D01*
X-395036Y-149555D01*
X-395910Y-147513D01*
X-396346Y-145180D01*
Y-142846D01*
X-395910Y-140513D01*
X-395036Y-138471D01*
X-393726Y-136722D01*
X-392198Y-135555D01*
X-390451Y-135263D01*
X-388705Y-135555D01*
X-387176Y-136722D01*
X-385866Y-138471D01*
X-384992Y-140513D01*
X-384556Y-142846D01*
Y-145180D01*
X-384992Y-147513D01*
X-385866Y-149555D01*
X-387176Y-151305D01*
X-388705Y-152471D01*
X-390451Y-152763D01*
G01X-377536D02*
X-368366Y-135263D01*
G01X-377536D02*
X-368366Y-152763D01*
G01X-362001Y-158596D02*
X-348901D01*
G01X-342099Y-152763D02*
Y-135263D01*
X-333803D01*
G01X-336859Y-143721D02*
X-342099D01*
G01X-325910Y-152763D02*
X-320451Y-135263D01*
X-314992Y-152763D01*
G01X-316958Y-146638D02*
X-323945D01*
G01X-307973Y-152763D02*
Y-135263D01*
X-297929Y-152763D01*
Y-135263D01*
G01X-263148Y-136722D02*
X-264458Y-135846D01*
X-265986Y-135263D01*
X-267733D01*
X-269698Y-136138D01*
X-271226Y-137596D01*
X-272318Y-139347D01*
X-273191Y-142263D01*
X-273410Y-144888D01*
X-272973Y-147513D01*
X-272318Y-149263D01*
X-271008Y-151013D01*
X-269479Y-152180D01*
X-267951Y-152763D01*
X-266423D01*
X-264894Y-152180D01*
X-263584Y-151305D01*
X-262492Y-150139D01*
G01X-250451Y-152763D02*
X-252198Y-152471D01*
X-253726Y-151305D01*
X-255036Y-149555D01*
X-255910Y-147513D01*
X-256346Y-145180D01*
Y-142846D01*
X-255910Y-140513D01*
X-255036Y-138471D01*
X-253726Y-136722D01*
X-252198Y-135555D01*
X-250451Y-135263D01*
X-248705Y-135555D01*
X-247176Y-136722D01*
X-245866Y-138471D01*
X-244992Y-140513D01*
X-244556Y-142846D01*
Y-145180D01*
X-244992Y-147513D01*
X-245866Y-149555D01*
X-247176Y-151305D01*
X-248705Y-152471D01*
X-250451Y-152763D01*
G01X-237973D02*
Y-135263D01*
X-227929Y-152763D01*
Y-135263D01*
G01X-215451D02*
Y-152763D01*
G01X-220473Y-135263D02*
X-210429D01*
G01X-202318Y-152763D02*
Y-135263D01*
X-196859D01*
X-195113Y-136138D01*
X-194021Y-137305D01*
X-193584Y-139638D01*
X-194021Y-141972D01*
X-195331Y-143430D01*
X-196859Y-144305D01*
X-202318D01*
G01X-196859D02*
X-193584Y-152763D01*
G01X-180451D02*
X-182198Y-152471D01*
X-183726Y-151305D01*
X-185036Y-149555D01*
X-185910Y-147513D01*
X-186346Y-145180D01*
Y-142846D01*
X-185910Y-140513D01*
X-185036Y-138471D01*
X-183726Y-136722D01*
X-182198Y-135555D01*
X-180451Y-135263D01*
X-178705Y-135555D01*
X-177176Y-136722D01*
X-175866Y-138471D01*
X-174992Y-140513D01*
X-174556Y-142846D01*
Y-145180D01*
X-174992Y-147513D01*
X-175866Y-149555D01*
X-177176Y-151305D01*
X-178705Y-152471D01*
X-180451Y-152763D01*
G01X-167318Y-135263D02*
Y-152763D01*
X-158584D01*
G01X-126205Y-143430D02*
X-125331Y-142555D01*
X-124676Y-141097D01*
X-124239Y-139054D01*
X-124676Y-137305D01*
X-125549Y-136138D01*
X-127078Y-135263D01*
X-132973D01*
Y-152763D01*
X-125768D01*
X-124239Y-151597D01*
X-123366Y-149846D01*
X-122929Y-147805D01*
X-123366Y-145763D01*
X-124676Y-144013D01*
X-126205Y-143430D01*
X-132973D01*
G01X-110451Y-152763D02*
X-112198Y-152471D01*
X-113726Y-151305D01*
X-115036Y-149555D01*
X-115910Y-147513D01*
X-116346Y-145180D01*
Y-142846D01*
X-115910Y-140513D01*
X-115036Y-138471D01*
X-113726Y-136722D01*
X-112198Y-135555D01*
X-110451Y-135263D01*
X-108705Y-135555D01*
X-107176Y-136722D01*
X-105866Y-138471D01*
X-104992Y-140513D01*
X-104556Y-142846D01*
Y-145180D01*
X-104992Y-147513D01*
X-105866Y-149555D01*
X-107176Y-151305D01*
X-108705Y-152471D01*
X-110451Y-152763D01*
G01X-98410D02*
X-92951Y-135263D01*
X-87492Y-152763D01*
G01X-89458Y-146638D02*
X-96445D01*
G01X-79818Y-152763D02*
Y-135263D01*
X-74359D01*
X-72613Y-136138D01*
X-71521Y-137305D01*
X-71084Y-139638D01*
X-71521Y-141972D01*
X-72831Y-143430D01*
X-74359Y-144305D01*
X-79818D01*
G01X-74359D02*
X-71084Y-152763D01*
G01X-62754D02*
Y-135263D01*
X-58388D01*
X-56641Y-136138D01*
X-55331Y-137305D01*
X-54239Y-139054D01*
X-53366Y-141097D01*
X-53148Y-144013D01*
X-53366Y-146930D01*
X-54239Y-148972D01*
X-55331Y-150722D01*
X-56641Y-151888D01*
X-58388Y-152763D01*
X-62754D01*
G01X-282378Y-107763D02*
Y-90263D01*
X-276701Y-104846D01*
X-271024Y-90263D01*
Y-107763D01*
G01X-259201D02*
X-260511Y-107471D01*
X-261821Y-106305D01*
X-262695Y-104263D01*
X-263131Y-101930D01*
X-262695Y-99596D01*
X-261821Y-97555D01*
X-260511Y-96388D01*
X-259201Y-96097D01*
X-257891Y-96388D01*
X-256581Y-97555D01*
X-255708Y-99596D01*
X-255489Y-101930D01*
X-255708Y-104263D01*
X-256581Y-106305D01*
X-257891Y-107471D01*
X-259201Y-107763D01*
G01X-237771Y-90263D02*
Y-107763D01*
G01Y-105139D02*
X-238644Y-106597D01*
X-239955Y-107471D01*
X-241483Y-107763D01*
X-243229Y-107180D01*
X-244539Y-105722D01*
X-245413Y-103972D01*
X-245631Y-101930D01*
X-245413Y-99888D01*
X-244539Y-98138D01*
X-243229Y-96680D01*
X-241483Y-96097D01*
X-239955Y-96388D01*
X-238863Y-96972D01*
X-237771Y-98138D01*
G01X-227476Y-99888D02*
X-220489D01*
X-221144Y-97846D01*
X-222236Y-96680D01*
X-223764Y-96097D01*
X-225293Y-96388D01*
X-226603Y-97263D01*
X-227476Y-99305D01*
X-227913Y-101055D01*
Y-102805D01*
X-227476Y-104555D01*
X-226384Y-106305D01*
X-225074Y-107471D01*
X-223546Y-107763D01*
X-222018Y-107180D01*
X-220489Y-105430D01*
G01X-206701Y-107763D02*
Y-90263D01*
G01X-14018Y-107763D02*
Y-90263D01*
X-8778D01*
X-7031Y-91138D01*
X-5721Y-93180D01*
X-5284Y-95513D01*
X-5721Y-97846D01*
X-6813Y-99596D01*
X-8778Y-100472D01*
X-14018D01*
G01X12652Y-91722D02*
X11342Y-90846D01*
X9814Y-90263D01*
X8067D01*
X6102Y-91138D01*
X4574Y-92596D01*
X3482Y-94347D01*
X2609Y-97263D01*
X2390Y-99888D01*
X2827Y-102513D01*
X3482Y-104263D01*
X4792Y-106013D01*
X6321Y-107180D01*
X7849Y-107763D01*
X9377D01*
X10906Y-107180D01*
X12216Y-106305D01*
X13308Y-105139D01*
G01X27095Y-98430D02*
X27969Y-97555D01*
X28624Y-96097D01*
X29061Y-94054D01*
X28624Y-92305D01*
X27751Y-91138D01*
X26222Y-90263D01*
X20327D01*
Y-107763D01*
X27532D01*
X29061Y-106597D01*
X29934Y-104846D01*
X30371Y-102805D01*
X29934Y-100763D01*
X28624Y-99013D01*
X27095Y-98430D01*
X20327D01*
G01X36299Y-113596D02*
X49399D01*
G01X55327Y-107763D02*
Y-90263D01*
X65371Y-107763D01*
Y-90263D01*
G01X77849Y-107763D02*
X76102Y-107471D01*
X74574Y-106305D01*
X73264Y-104555D01*
X72390Y-102513D01*
X71954Y-100180D01*
Y-97846D01*
X72390Y-95513D01*
X73264Y-93471D01*
X74574Y-91722D01*
X76102Y-90555D01*
X77849Y-90263D01*
X79595Y-90555D01*
X81124Y-91722D01*
X82434Y-93471D01*
X83308Y-95513D01*
X83744Y-97846D01*
Y-100180D01*
X83308Y-102513D01*
X82434Y-104555D01*
X81124Y-106305D01*
X79595Y-107471D01*
X77849Y-107763D01*
G01X-901Y-152763D02*
Y-135263D01*
X-3521Y-138763D01*
G01Y-152763D02*
X1719D01*
G01X12451Y-138180D02*
X13761Y-136430D01*
X15289Y-135555D01*
X17036Y-135263D01*
X19219Y-135846D01*
X20747Y-137305D01*
X21184Y-139054D01*
X20966Y-140805D01*
X20092Y-142263D01*
X15726Y-145180D01*
X13761Y-147221D01*
X12451Y-150139D01*
X12014Y-152763D01*
X21184D01*
G01X36719D02*
Y-135263D01*
X28640Y-147805D01*
X39558D01*
G01X46796Y-149263D02*
X48105Y-151305D01*
X49852Y-152471D01*
X51817Y-152763D01*
X53564Y-152471D01*
X55311Y-151013D01*
X56402Y-149263D01*
X56621Y-147513D01*
X56184Y-145472D01*
X54656Y-144013D01*
X53127Y-143430D01*
X51162D01*
G01X53127D02*
X54437Y-142555D01*
X55529Y-141097D01*
X55966Y-139347D01*
X55529Y-137596D01*
X54437Y-136138D01*
X52472Y-135263D01*
X50507Y-135555D01*
X48542Y-136722D01*
G01X64296Y-149263D02*
X65605Y-151305D01*
X67352Y-152471D01*
X69317Y-152763D01*
X71064Y-152471D01*
X72811Y-151013D01*
X73902Y-149263D01*
X74121Y-147513D01*
X73684Y-145472D01*
X72156Y-144013D01*
X70627Y-143430D01*
X68662D01*
G01X70627D02*
X71937Y-142555D01*
X73029Y-141097D01*
X73466Y-139347D01*
X73029Y-137596D01*
X71937Y-136138D01*
X69972Y-135263D01*
X68007Y-135555D01*
X66042Y-136722D01*
G01X128690Y-90263D02*
X134149Y-107763D01*
X139608Y-90263D01*
G01X156016Y-107763D02*
X147282D01*
Y-90263D01*
X156016D01*
G01X152522Y-98721D02*
X147282D01*
G01X164782Y-107763D02*
Y-90263D01*
X170241D01*
X171987Y-91138D01*
X173079Y-92305D01*
X173516Y-94638D01*
X173079Y-96972D01*
X171769Y-98430D01*
X170241Y-99305D01*
X164782D01*
G01X170241D02*
X173516Y-107763D01*
G01X186649Y-108346D02*
X186212Y-108055D01*
Y-107471D01*
X186649Y-107180D01*
X187086Y-107471D01*
Y-108055D01*
X186649Y-108346D01*
G01X147501Y-138180D02*
X148811Y-136430D01*
X150339Y-135555D01*
X152086Y-135263D01*
X154269Y-135846D01*
X155797Y-137305D01*
X156234Y-139054D01*
X156016Y-140805D01*
X155142Y-142263D01*
X150776Y-145180D01*
X148811Y-147221D01*
X147501Y-150139D01*
X147064Y-152763D01*
X156234D01*
G01X163690D02*
X169149Y-135263D01*
X174608Y-152763D01*
G01X172642Y-146638D02*
X165655D01*
G01X253482Y-90263D02*
Y-107763D01*
X262216D01*
G01X279279D02*
Y-96097D01*
G01Y-98138D02*
X278406Y-96972D01*
X277095Y-96388D01*
X275567Y-96097D01*
X274039Y-96680D01*
X272729Y-97846D01*
X271855Y-99596D01*
X271419Y-101930D01*
X271855Y-104263D01*
X272729Y-106013D01*
X274039Y-107180D01*
X275567Y-107763D01*
X277095Y-107471D01*
X278406Y-106597D01*
X279279Y-105430D01*
G01X288264Y-113013D02*
X289574Y-113596D01*
X291321Y-113013D01*
X292412Y-111847D01*
X293286Y-110388D01*
X294595Y-105722D01*
X297434Y-96097D01*
G01X290447D02*
X294595Y-105722D01*
G01X307074Y-99888D02*
X314061D01*
X313406Y-97846D01*
X312314Y-96680D01*
X310786Y-96097D01*
X309257Y-96388D01*
X307947Y-97263D01*
X307074Y-99305D01*
X306637Y-101055D01*
Y-102805D01*
X307074Y-104555D01*
X308166Y-106305D01*
X309476Y-107471D01*
X311004Y-107763D01*
X312532Y-107180D01*
X314061Y-105430D01*
G01X324792Y-107763D02*
Y-96097D01*
G01Y-98430D02*
X325884Y-97263D01*
X326976Y-96388D01*
X328504Y-96097D01*
X329595Y-96388D01*
X330906Y-97263D01*
G01X342074Y-105722D02*
X343166Y-106888D01*
X344694Y-107763D01*
X346004D01*
X347314Y-107180D01*
X348187Y-106305D01*
X348624Y-105139D01*
X348406Y-103388D01*
X347532Y-102513D01*
X343602Y-100763D01*
X342729Y-98721D01*
X343166Y-97263D01*
X344039Y-96388D01*
X345349Y-96097D01*
X346659Y-96388D01*
X347969Y-97263D01*
G01X262232Y-135263D02*
Y-152763D01*
X270966D01*
G01X279951Y-138180D02*
X281261Y-136430D01*
X282789Y-135555D01*
X284536Y-135263D01*
X286719Y-135846D01*
X288247Y-137305D01*
X288684Y-139054D01*
X288466Y-140805D01*
X287592Y-142263D01*
X283226Y-145180D01*
X281261Y-147221D01*
X279951Y-150139D01*
X279514Y-152763D01*
X288684D01*
G01X302909Y-144013D02*
X307276D01*
Y-149263D01*
X305966Y-151013D01*
X304437Y-152180D01*
X302254Y-152763D01*
X300071Y-152180D01*
X298542Y-151013D01*
X297232Y-149263D01*
X296359Y-147221D01*
X295922Y-144888D01*
Y-142846D01*
X296359Y-141097D01*
X297232Y-139054D01*
X298542Y-137305D01*
X299852Y-136138D01*
X301599Y-135263D01*
X303127D01*
X304874Y-135846D01*
X306184Y-137013D01*
G01X314077Y-152763D02*
Y-135263D01*
X324121Y-152763D01*
Y-135263D01*
G01X331796Y-152763D02*
Y-135263D01*
X336162D01*
X337909Y-136138D01*
X339219Y-137305D01*
X340311Y-139054D01*
X341184Y-141097D01*
X341402Y-144013D01*
X341184Y-146930D01*
X340311Y-148972D01*
X339219Y-150722D01*
X337909Y-151888D01*
X336162Y-152763D01*
X331796D01*
G01X404346Y-107763D02*
Y-90263D01*
X408712D01*
X410459Y-91138D01*
X411769Y-92305D01*
X412861Y-94054D01*
X413734Y-96097D01*
X413952Y-99013D01*
X413734Y-101930D01*
X412861Y-103972D01*
X411769Y-105722D01*
X410459Y-106888D01*
X408712Y-107763D01*
X404346D01*
G01X423374Y-99888D02*
X430361D01*
X429706Y-97846D01*
X428614Y-96680D01*
X427086Y-96097D01*
X425557Y-96388D01*
X424247Y-97263D01*
X423374Y-99305D01*
X422937Y-101055D01*
Y-102805D01*
X423374Y-104555D01*
X424466Y-106305D01*
X425776Y-107471D01*
X427304Y-107763D01*
X428832Y-107180D01*
X430361Y-105430D01*
G01X440874Y-105722D02*
X441966Y-106888D01*
X443494Y-107763D01*
X444804D01*
X446114Y-107180D01*
X446987Y-106305D01*
X447424Y-105139D01*
X447206Y-103388D01*
X446332Y-102513D01*
X442402Y-100763D01*
X441529Y-98721D01*
X441966Y-97263D01*
X442839Y-96388D01*
X444149Y-96097D01*
X445459Y-96388D01*
X446769Y-97263D01*
G01X461649Y-96097D02*
Y-107763D01*
G01Y-91430D02*
X461212Y-91138D01*
Y-90555D01*
X461649Y-90263D01*
X462086Y-90555D01*
Y-91138D01*
X461649Y-91430D01*
G01X476092Y-112138D02*
X477621Y-113305D01*
X479367Y-113596D01*
X480895Y-113305D01*
X482206Y-111847D01*
X483079Y-109805D01*
Y-96097D01*
G01Y-98430D02*
X482206Y-97263D01*
X480895Y-96388D01*
X479367Y-96097D01*
X477621Y-96680D01*
X476529Y-97846D01*
X475655Y-99888D01*
X475219Y-101930D01*
X475437Y-103680D01*
X476311Y-105722D01*
X477621Y-107180D01*
X479367Y-107763D01*
X480677Y-107471D01*
X482206Y-106305D01*
X483079Y-105139D01*
G01X492937Y-107763D02*
Y-96097D01*
G01Y-99013D02*
X493811Y-97555D01*
X495121Y-96388D01*
X496867Y-96097D01*
X498395Y-96388D01*
X499706Y-97555D01*
X500361Y-99596D01*
Y-107763D01*
G01X510874Y-99888D02*
X517861D01*
X517206Y-97846D01*
X516114Y-96680D01*
X514586Y-96097D01*
X513057Y-96388D01*
X511747Y-97263D01*
X510874Y-99305D01*
X510437Y-101055D01*
Y-102805D01*
X510874Y-104555D01*
X511966Y-106305D01*
X513276Y-107471D01*
X514804Y-107763D01*
X516332Y-107180D01*
X517861Y-105430D01*
G01X528592Y-107763D02*
Y-96097D01*
G01Y-98430D02*
X529684Y-97263D01*
X530776Y-96388D01*
X532304Y-96097D01*
X533395Y-96388D01*
X534706Y-97263D01*
G01X429722Y-152763D02*
Y-135263D01*
X435399Y-149846D01*
X441076Y-135263D01*
Y-152763D01*
G01X452899D02*
X451152Y-152471D01*
X449624Y-151305D01*
X448314Y-149555D01*
X447440Y-147513D01*
X447004Y-145180D01*
Y-142846D01*
X447440Y-140513D01*
X448314Y-138471D01*
X449624Y-136722D01*
X451152Y-135555D01*
X452899Y-135263D01*
X454645Y-135555D01*
X456174Y-136722D01*
X457484Y-138471D01*
X458358Y-140513D01*
X458794Y-142846D01*
Y-145180D01*
X458358Y-147513D01*
X457484Y-149555D01*
X456174Y-151305D01*
X454645Y-152471D01*
X452899Y-152763D01*
G01X465814Y-150430D02*
X467561Y-151888D01*
X469526Y-152763D01*
X471272D01*
X473019Y-151888D01*
X474329Y-150430D01*
X474984Y-148388D01*
X474547Y-146347D01*
X473456Y-144596D01*
X471491Y-143430D01*
X468871Y-142846D01*
X467342Y-141680D01*
X466687Y-139638D01*
X467124Y-137596D01*
X468216Y-136138D01*
X469744Y-135263D01*
X471272D01*
X472801Y-135846D01*
X474111Y-137305D01*
G01X483314Y-150430D02*
X485061Y-151888D01*
X487026Y-152763D01*
X488772D01*
X490519Y-151888D01*
X491829Y-150430D01*
X492484Y-148388D01*
X492047Y-146347D01*
X490956Y-144596D01*
X488991Y-143430D01*
X486371Y-142846D01*
X484842Y-141680D01*
X484187Y-139638D01*
X484624Y-137596D01*
X485716Y-136138D01*
X487244Y-135263D01*
X488772D01*
X490301Y-135846D01*
X491611Y-137305D01*
G01X509766Y-152763D02*
X501032D01*
Y-135263D01*
X509766D01*
G01X506272Y-143721D02*
X501032D01*
G01X575349Y-152763D02*
Y-135263D01*
X572729Y-138763D01*
G01Y-152763D02*
X577969D01*
G01X588701Y-138180D02*
X590011Y-136430D01*
X591539Y-135555D01*
X593286Y-135263D01*
X595469Y-135846D01*
X596997Y-137305D01*
X597434Y-139054D01*
X597216Y-140805D01*
X596342Y-142263D01*
X591976Y-145180D01*
X590011Y-147221D01*
X588701Y-150139D01*
X588264Y-152763D01*
X597434D01*
G01X606419Y-153346D02*
X614279Y-135263D01*
G01X627849Y-152763D02*
Y-135263D01*
X625229Y-138763D01*
G01Y-152763D02*
X630469D01*
G01X645349D02*
Y-135263D01*
X642729Y-138763D01*
G01Y-152763D02*
X647969D01*
G01X658919Y-153346D02*
X666779Y-135263D01*
G01X676201Y-138180D02*
X677511Y-136430D01*
X679039Y-135555D01*
X680786Y-135263D01*
X682969Y-135846D01*
X684497Y-137305D01*
X684934Y-139054D01*
X684716Y-140805D01*
X683842Y-142263D01*
X679476Y-145180D01*
X677511Y-147221D01*
X676201Y-150139D01*
X675764Y-152763D01*
X684934D01*
G01X697849Y-135263D02*
X696102Y-135846D01*
X694792Y-137305D01*
X693919Y-139054D01*
X693264Y-141388D01*
X693046Y-144013D01*
X693264Y-146638D01*
X693919Y-148972D01*
X694792Y-150722D01*
X696102Y-152180D01*
X697849Y-152763D01*
X699595Y-152180D01*
X700906Y-150722D01*
X701779Y-148972D01*
X702434Y-146638D01*
X702652Y-144013D01*
X702434Y-141388D01*
X701779Y-139054D01*
X700906Y-137305D01*
X699595Y-135846D01*
X697849Y-135263D01*
G01X715349Y-152763D02*
Y-135263D01*
X712729Y-138763D01*
G01Y-152763D02*
X717969D01*
G01X728046Y-150139D02*
X729355Y-151597D01*
X730884Y-152471D01*
X732849Y-152763D01*
X734814Y-152180D01*
X736342Y-151013D01*
X737434Y-148972D01*
X737652Y-146638D01*
X737216Y-144305D01*
X736124Y-142846D01*
X734595Y-141680D01*
X733067Y-141388D01*
X731539Y-141680D01*
X729574Y-142846D01*
X730229Y-135263D01*
X736124D01*
G01X623046Y-107763D02*
Y-90263D01*
X627412D01*
X629159Y-91138D01*
X630469Y-92305D01*
X631561Y-94054D01*
X632434Y-96097D01*
X632652Y-99013D01*
X632434Y-101930D01*
X631561Y-103972D01*
X630469Y-105722D01*
X629159Y-106888D01*
X627412Y-107763D01*
X623046D01*
G01X649279D02*
Y-96097D01*
G01Y-98138D02*
X648406Y-96972D01*
X647095Y-96388D01*
X645567Y-96097D01*
X644039Y-96680D01*
X642729Y-97846D01*
X641855Y-99596D01*
X641419Y-101930D01*
X641855Y-104263D01*
X642729Y-106013D01*
X644039Y-107180D01*
X645567Y-107763D01*
X647095Y-107471D01*
X648406Y-106597D01*
X649279Y-105430D01*
G01X662849Y-90263D02*
Y-107763D01*
G01X659792Y-96097D02*
X665906D01*
G01X677074Y-99888D02*
X684061D01*
X683406Y-97846D01*
X682314Y-96680D01*
X680786Y-96097D01*
X679257Y-96388D01*
X677947Y-97263D01*
X677074Y-99305D01*
X676637Y-101055D01*
Y-102805D01*
X677074Y-104555D01*
X678166Y-106305D01*
X679476Y-107471D01*
X681004Y-107763D01*
X682532Y-107180D01*
X684061Y-105430D01*
M02*
